# Altium SchDoc records: GPS_IMU_SENSORS.SchDoc
|HEADER=Protel for Windows - Schematic Capture Binary File Version 5.0|Weight=1538|MinorVersion=2
|RECORD=31|FontIdCount=8|Size1=10|FontName1=Times New Roman|Size2=12|FontName2=Arial|Size3=14|FontName3=Arial|Size4=24|FontName4=Times New Roman|Size5=10|Underline5=T|FontName5=Times New Roman|Size6=8|FontName6=Arial|Size7=10|FontName7=Arial|Size8=12|Underline8=T|FontName8=Arial|UseMBCS=T|IsBOC=T|HotSpotGridOn=T|HotSpotGridSize=1|SheetStyle=12|SystemFont=7|BorderOn=T|SheetNumberSpaceSize=12|AreaColor=16317695|SnapGridOn=T|SnapGridSize=1|VisibleGridOn=T|VisibleGridSize=10|CustomX=2338|CustomX_Frac=58268|CustomY=1653|CustomY_Frac=54331|CustomXZones=8|CustomYZones=6|CustomMarginWidth=19|CustomMarginWidth_Frac=80000|ShowTemplateGraphics=T|TemplateFileName=C:\Users\<user>\Documents\Altium\AD20\Templates\Timecard.SchDot|Display_Unit=0
|RECORD=39|IsNotAccesible=T|OwnerPartId=-1|FileName=C:\Users\<user>\Documents\Altium\AD20\Templates\Timecard.SchDot
|RECORD=4|OwnerIndex=1|OwnerPartId=-1|Location.X=1594|Location.Y=39|Color=8388608|FontID=8|Text=timingcard.com|URL=http://timingcard.com
|RECORD=6|OwnerIndex=1|IndexInSheet=1|OwnerPartId=-1|LocationCount=2|X1=1680|Y1=35|X2=1576|Y2=35
|RECORD=4|OwnerIndex=1|IndexInSheet=2|OwnerPartId=-1|Location.X=1614|Location.X_Frac=42446|Location.Y=19|Location.Y_Frac=96838|FontID=2|Text==SheetNumber
|RECORD=4|OwnerIndex=1|IndexInSheet=3|OwnerPartId=-1|Location.X=1581|Location.X_Frac=42446|Location.Y=29|Location.Y_Frac=96838|Justification=3|FontID=6|Text=SHEET
|RECORD=4|OwnerIndex=1|IndexInSheet=4|OwnerPartId=-1|Location.X=1639|Location.X_Frac=42446|Location.Y=29|Location.Y_Frac=96838|Justification=3|FontID=6|Text=OF
|RECORD=6|OwnerIndex=1|IndexInSheet=5|OwnerPartId=-1|LineWidth=1|LocationCount=2|X1=1679|X1_Frac=42446|Y1=105|Y1_Frac=96838|X2=1576|Y2=106
|RECORD=4|OwnerIndex=1|IndexInSheet=6|OwnerPartId=-1|Location.X=1658|Location.Y=20|FontID=2|Text==SheetTotal
|RECORD=30|OwnerIndex=1|IndexInSheet=7|OwnerPartId=-1|Location.X=1578|Location.Y=53|Corner.X=1673|Corner.X_Frac=88801|Corner.Y=103|KeepAspect=T|FileName=C:\Users\<user>\Desktop\Timecard Logo\TIMECARD.jpg
|RECORD=6|OwnerIndex=1|IndexInSheet=8|OwnerPartId=-1|LineWidth=1|LocationCount=2|X1=1576|X1_Frac=3162|Y1=105|Y1_Frac=42446|X2=1576|Y2=20
|RECORD=6|OwnerIndex=1|IndexInSheet=9|OwnerPartId=-1|LocationCount=2|X1=1680|Y1=51|X2=1576|Y2=51
|RECORD=41|IndexInSheet=1|OwnerPartId=-1|Color=8388608|FontID=1|IsHidden=T|Text=*|Name=CurrentTime|ReadOnlyState=1
|RECORD=41|IndexInSheet=2|OwnerPartId=-1|Color=8388608|FontID=1|IsHidden=T|Text=*|Name=CurrentDate|ReadOnlyState=1
|RECORD=41|IndexInSheet=3|OwnerPartId=-1|Color=8388608|FontID=1|IsHidden=T|Text=*|Name=Time|ReadOnlyState=1
|RECORD=41|IndexInSheet=4|OwnerPartId=-1|Color=8388608|FontID=1|IsHidden=T|Text=*|Name=Date|ReadOnlyState=1
|RECORD=41|IndexInSheet=5|OwnerPartId=-1|Color=8388608|FontID=1|IsHidden=T|Text=*|Name=DocumentFullPathAndName|ReadOnlyState=1
|RECORD=41|IndexInSheet=6|OwnerPartId=-1|Color=8388608|FontID=1|IsHidden=T|Text=*|Name=DocumentName|ReadOnlyState=1
|RECORD=41|IndexInSheet=7|OwnerPartId=-1|Color=8388608|FontID=1|IsHidden=T|Text=*|Name=ModifiedDate|ReadOnlyState=1
|RECORD=41|IndexInSheet=8|OwnerPartId=-1|Color=8388608|FontID=1|IsHidden=T|Text=*|Name=ApprovedBy|ReadOnlyState=1
|RECORD=41|IndexInSheet=9|OwnerPartId=-1|Color=8388608|FontID=1|IsHidden=T|Text=*|Name=CheckedBy|ReadOnlyState=1
|RECORD=41|IndexInSheet=10|OwnerPartId=-1|Color=8388608|FontID=1|IsHidden=T|Text=<name>|Name=Author|ReadOnlyState=1
|RECORD=41|IndexInSheet=11|OwnerPartId=-1|Color=8388608|FontID=1|IsHidden=T|Text=*|Name=CompanyName|ReadOnlyState=1
|RECORD=41|IndexInSheet=12|OwnerPartId=-1|Color=8388608|FontID=1|IsHidden=T|Text=*|Name=DrawnBy|ReadOnlyState=1
|RECORD=41|IndexInSheet=13|OwnerPartId=-1|Color=8388608|FontID=1|IsHidden=T|Text=*|Name=Engineer|ReadOnlyState=1
|RECORD=41|IndexInSheet=14|OwnerPartId=-1|Color=8388608|FontID=1|IsHidden=T|Text=*|Name=Organization|ReadOnlyState=1
|RECORD=41|IndexInSheet=15|OwnerPartId=-1|Color=8388608|FontID=1|IsHidden=T|Text=*|Name=Address1|ReadOnlyState=1
|RECORD=41|IndexInSheet=16|OwnerPartId=-1|Color=8388608|FontID=1|IsHidden=T|Text=*|Name=Address2|ReadOnlyState=1
|RECORD=41|IndexInSheet=17|OwnerPartId=-1|Color=8388608|FontID=1|IsHidden=T|Text=*|Name=Address3|ReadOnlyState=1
|RECORD=41|IndexInSheet=18|OwnerPartId=-1|Color=8388608|FontID=1|IsHidden=T|Text=*|Name=Address4|ReadOnlyState=1
|RECORD=41|IndexInSheet=19|OwnerPartId=-1|Color=8388608|FontID=1|IsHidden=T|Text=Gransmaster GPS & IMU|Name=Title|ReadOnlyState=1
|RECORD=41|IndexInSheet=20|OwnerPartId=-1|Color=8388608|FontID=1|IsHidden=T|Text=*|Name=DocumentNumber|ReadOnlyState=1
|RECORD=41|IndexInSheet=21|OwnerPartId=-1|Color=8388608|FontID=1|IsHidden=T|Text=A|Name=Revision|ReadOnlyState=1
|RECORD=41|IndexInSheet=22|OwnerPartId=-1|Color=8388608|FontID=1|IsHidden=T|Text=5|Name=SheetNumber|ReadOnlyState=1
|RECORD=41|IndexInSheet=23|OwnerPartId=-1|Color=8388608|FontID=1|IsHidden=T|Text=7|Name=SheetTotal|ReadOnlyState=1
|RECORD=41|IndexInSheet=24|OwnerPartId=-1|Color=8388608|FontID=1|IsHidden=T|Text=*|Name=Rule|ReadOnlyState=1
|RECORD=41|IndexInSheet=25|OwnerPartId=-1|Color=8388608|FontID=1|IsHidden=T|Text=*|Name=ImagePath|ReadOnlyState=1
|RECORD=41|IndexInSheet=26|OwnerPartId=-1|Color=8388608|FontID=1|IsHidden=T|Text=*|Name=ProjectName|ReadOnlyState=1
|RECORD=41|IndexInSheet=27|OwnerPartId=-1|Color=8388608|FontID=1|IsHidden=T|Text=*|Name=Application_BuildNumber|ReadOnlyState=1
|RECORD=41|IndexInSheet=28|OwnerPartId=-1|Location.X=21474|Location.X_Frac=83647|Location.Y=21464|Location.Y_Frac=83647|Color=8388608|FontID=1|IsHidden=T|Text=01910|Name=Customer
|RECORD=41|IndexInSheet=29|OwnerPartId=-1|Location.X=1000|Location.Y=10|Color=8388608|FontID=1|IsHidden=T|Text=*|Name=DocStatus
|RECORD=17|IndexInSheet=30|OwnerPartId=-1|ShowNetName=T|Location.X=270|Location.Y=950|Orientation=1|Color=128|FontID=1|Text=+5.0V
|RECORD=17|IndexInSheet=31|OwnerPartId=-1|Style=4|ShowNetName=T|Location.X=690|Location.Y=860|Orientation=3|Color=128|FontID=1|Text=GND
|RECORD=17|IndexInSheet=32|OwnerPartId=-1|ShowNetName=T|Location.X=170|Location.Y=950|Orientation=1|Color=128|FontID=1|Text=+3.3V
|RECORD=17|IndexInSheet=33|OwnerPartId=-1|Style=4|ShowNetName=T|Location.X=170|Location.Y=870|Orientation=3|Color=128|FontID=1|Text=GND
|RECORD=17|IndexInSheet=34|OwnerPartId=-1|Style=4|ShowNetName=T|Location.X=270|Location.Y=870|Orientation=3|Color=128|FontID=1|Text=GND
|RECORD=17|IndexInSheet=35|OwnerPartId=-1|ShowNetName=T|Location.X=760|Location.Y=920|Color=255|FontID=1|Text=GPS1_TP2|IsCrossSheetConnector=T
|RECORD=17|IndexInSheet=36|OwnerPartId=-1|ShowNetName=T|Location.X=760|Location.Y=910|Color=255|FontID=1|Text=GPS1_TP1|IsCrossSheetConnector=T
|RECORD=17|IndexInSheet=37|OwnerPartId=-1|ShowNetName=T|Location.X=760|Location.Y=900|Color=255|FontID=1|Text=GPS1_RX|IsCrossSheetConnector=T
|RECORD=17|IndexInSheet=38|OwnerPartId=-1|ShowNetName=T|Location.X=420|Location.Y=910|Orientation=2|Color=255|FontID=1|Text=GPS1_TX|IsCrossSheetConnector=T
|RECORD=17|IndexInSheet=39|OwnerPartId=-1|ShowNetName=T|Location.X=420|Location.Y=900|Orientation=2|Color=255|FontID=1|Text=GPS1_RST|IsCrossSheetConnector=T
|RECORD=4|IndexInSheet=40|OwnerPartId=-1|Location.X=570|Location.Y=1000|Color=8388608|FontID=4|Text=GPS
|RECORD=1|LibReference=CAP_0805_10UF_25V|ComponentDescription=CAP, CER, 10.UF, 25V, 10%, X5R, 0805|PartCount=2|DisplayModeCount=1|IndexInSheet=41|OwnerPartId=-1|Location.X=150|Location.Y=860|CurrentPartId=1|LibraryPath=*|SourceLibraryName=Capacitors.IntLib|TargetFileName=*|AreaColor=11599871|Color=128|PartIDLocked=F|DesignItemId=CAP_0805_10UF_25V|AllPinCount=2
|RECORD=41|OwnerIndex=52|OwnerPartId=-1|Location.X=150|Location.Y=860|Color=8388608|FontID=2|IsHidden=T|Text=TAIYO YUDEN|Name=MFG NAME
|RECORD=41|OwnerIndex=52|IndexInSheet=1|OwnerPartId=-1|Location.X=150|Location.Y=860|Color=8388608|FontID=2|IsHidden=T|Text=TMK212BBJ106KG-T|Name=MFG PART NUM
|RECORD=41|OwnerIndex=52|IndexInSheet=2|OwnerPartId=-1|Location.X=150|Location.Y=860|Color=8388608|FontID=2|IsHidden=T|Text=10/23/2013|Name=MODIFY DATE
|RECORD=41|OwnerIndex=52|IndexInSheet=3|OwnerPartId=-1|Location.X=150|Location.Y=860|Color=8388608|FontID=2|IsHidden=T|Text=CAP, CER|Name=CATEGORY
|RECORD=41|OwnerIndex=52|IndexInSheet=4|OwnerPartId=-1|Location.X=148|Location.Y=872|Location.Y_Frac=50000|Color=8388608|FontID=2|IsHidden=T|Text=4/11/2006 3:37:28 PM|Name=Date
|RECORD=41|OwnerIndex=52|IndexInSheet=5|OwnerPartId=-1|Location.X=156|Location.Y=934|Location.Y_Frac=48252|Color=8388608|FontID=2|IsHidden=T|Text=*|Name=SHEETPART
|RECORD=41|OwnerIndex=52|IndexInSheet=6|OwnerPartId=-1|Location.X=156|Location.Y=934|Location.Y_Frac=48252|Color=8388608|FontID=2|IsHidden=T|Text=10%|Name=P1
|RECORD=41|OwnerIndex=52|IndexInSheet=7|OwnerPartId=-1|Location.X=156|Location.Y=934|Location.Y_Frac=48252|Color=8388608|FontID=2|IsHidden=T|Text=85C|Name=MAXTEMP
|RECORD=41|OwnerIndex=52|IndexInSheet=8|OwnerPartId=-1|Location.X=156|Location.Y=934|Location.Y_Frac=48252|Color=8388608|FontID=2|IsHidden=T|Text=-55C|Name=MINTEMP
|RECORD=41|OwnerIndex=52|IndexInSheet=9|OwnerPartId=-1|Location.X=156|Location.Y=934|Location.Y_Frac=48252|Color=8388608|FontID=2|IsHidden=T|Name=OTHER
|RECORD=41|OwnerIndex=52|IndexInSheet=10|OwnerPartId=-1|Location.X=156|Location.Y=934|Location.Y_Frac=48252|Color=8388608|FontID=2|IsHidden=T|Text=25V|Name=P2
|RECORD=41|OwnerIndex=52|IndexInSheet=11|OwnerPartId=-1|Location.X=156|Location.Y=934|Location.Y_Frac=48252|Color=8388608|FontID=2|IsHidden=T|Text=X5R|Name=P3
|RECORD=41|OwnerIndex=52|IndexInSheet=12|OwnerPartId=-1|Location.X=156|Location.Y=934|Location.Y_Frac=48252|Color=8388608|FontID=2|IsHidden=T|Text=0805|Name=Size
|RECORD=41|OwnerIndex=52|IndexInSheet=13|OwnerPartId=-1|Location.X=156|Location.Y=934|Location.Y_Frac=48252|Color=8388608|FontID=2|IsHidden=T|Name=SUB
|RECORD=41|OwnerIndex=52|IndexInSheet=14|OwnerPartId=-1|Location.X=156|Location.Y=934|Location.Y_Frac=48252|Color=8388608|FontID=1|IsHidden=T|Text=CAP, CER, 10.UF, 10V, 10%, X5R, 0805|Name=DESC
|RECORD=41|OwnerIndex=52|IndexInSheet=15|OwnerPartId=-1|Location.X=156|Location.Y=933|Location.Y_Frac=98252|Color=8388608|FontID=1|IsHidden=T|Text=MOUSER|Name=Supplier 1|ReadOnlyState=1
|RECORD=41|OwnerIndex=52|IndexInSheet=16|OwnerPartId=-1|Location.X=156|Location.Y=933|Location.Y_Frac=98252|Color=8388608|FontID=1|IsHidden=T|Text=963-TMK212BBJ106KG-T|Name=Supplier Part Number 1|ReadOnlyState=1
|RECORD=41|OwnerIndex=52|IndexInSheet=17|OwnerPartId=-1|Location.X=180|Location.Y=890|Color=8388608|FontID=2|Text=10uF|Name=VALUE
|RECORD=2|OwnerIndex=52|OwnerPartId=1|FormalType=1|Electrical=4|PinConglomerate=35|PinLength=10|Location.X=170|Location.Y=890|Name=2|Designator=2|SwapIdPin=2|SwapIDPart=1|PinPropagationDelay=0.000000E+000
|RECORD=2|OwnerIndex=52|OwnerPartId=1|FormalType=1|Electrical=4|PinConglomerate=33|PinLength=10|Location.X=170|Location.Y=900|Name=1|Designator=1|SwapIdPin=1|SwapIDPart=1|PinPropagationDelay=0.000000E+000
|RECORD=13|OwnerIndex=52|IsNotAccesible=T|IndexInSheet=20|OwnerPartId=1|Location.X=170|Location.Y=892|Location.Y_Frac=50000|Corner.X=170|Corner.Y=890|LineWidth=1|Color=16711680
|RECORD=13|OwnerIndex=52|IsNotAccesible=T|IndexInSheet=21|OwnerPartId=1|Location.X=170|Location.Y=900|Corner.X=170|Corner.Y=897|Corner.Y_Frac=50000|LineWidth=1|Color=16711680
|RECORD=13|OwnerIndex=52|IsNotAccesible=T|IndexInSheet=22|OwnerPartId=1|Location.X=175|Location.Y=892|Location.Y_Frac=50000|Corner.X=165|Corner.Y=892|Corner.Y_Frac=50000|LineWidth=1|Color=16711680
|RECORD=13|OwnerIndex=52|IsNotAccesible=T|IndexInSheet=23|OwnerPartId=1|Location.X=175|Location.Y=897|Location.Y_Frac=50000|Corner.X=165|Corner.Y=897|Corner.Y_Frac=50000|LineWidth=1|Color=16711680
|RECORD=41|OwnerIndex=52|IndexInSheet=24|OwnerPartId=-1|Location.X=156|Location.Y=933|Location.Y_Frac=98951|Color=8388608|FontID=1|IsHidden=T|Text=<VALENTIUM>|Name=VALENTIUM PART NUM
|RECORD=34|OwnerIndex=52|IndexInSheet=-1|OwnerPartId=-1|Location.X=180|Location.Y=900|Color=8388608|FontID=3|Text=C58|Name=Designator|ReadOnlyState=1
|RECORD=41|OwnerIndex=52|IndexInSheet=-1|OwnerPartId=-1|Location.X=177|Location.X_Frac=50000|Location.Y=855|Color=8388608|FontID=2|IsHidden=T|Text=CAP_0805_10UF_25V|Name=Comment
|RECORD=44|OwnerIndex=52
|RECORD=45|OwnerIndex=82|IndexInSheet=-1|Description=Chip Capacitor, 0805, 2-Leads, Body 2.00x1.25mm, IPC Medium Density|UseComponentLibrary=T|ModelName=CAPC2012X14N|ModelType=PCBLIB|DatafileCount=1|ModelDatafileEntity0=CAPC2012X14N|ModelDatafileKind0=PCBLib|IsCurrent=T|DatalinksLocked=T|DatabaseDatalinksLocked=T|IntegratedModel=T|DatabaseModel=T
|RECORD=46|OwnerIndex=83
|RECORD=48|OwnerIndex=83
|RECORD=1|LibReference=CAP_0805_10UF_25V|ComponentDescription=CAP, CER, 10.UF, 25V, 10%, X5R, 0805|PartCount=2|DisplayModeCount=1|IndexInSheet=42|OwnerPartId=-1|Location.X=250|Location.Y=860|CurrentPartId=1|LibraryPath=*|SourceLibraryName=Capacitors.IntLib|TargetFileName=*|AreaColor=11599871|Color=128|PartIDLocked=F|DesignItemId=CAP_0805_10UF_25V|AllPinCount=2
|RECORD=41|OwnerIndex=86|OwnerPartId=-1|Location.X=250|Location.Y=860|Color=8388608|FontID=2|IsHidden=T|Text=TAIYO YUDEN|Name=MFG NAME
|RECORD=41|OwnerIndex=86|IndexInSheet=1|OwnerPartId=-1|Location.X=250|Location.Y=860|Color=8388608|FontID=2|IsHidden=T|Text=TMK212BBJ106KG-T|Name=MFG PART NUM
|RECORD=41|OwnerIndex=86|IndexInSheet=2|OwnerPartId=-1|Location.X=250|Location.Y=860|Color=8388608|FontID=2|IsHidden=T|Text=10/23/2013|Name=MODIFY DATE
|RECORD=41|OwnerIndex=86|IndexInSheet=3|OwnerPartId=-1|Location.X=250|Location.Y=860|Color=8388608|FontID=2|IsHidden=T|Text=CAP, CER|Name=CATEGORY
|RECORD=41|OwnerIndex=86|IndexInSheet=4|OwnerPartId=-1|Location.X=248|Location.Y=872|Location.Y_Frac=50000|Color=8388608|FontID=2|IsHidden=T|Text=4/11/2006 3:37:28 PM|Name=Date
|RECORD=41|OwnerIndex=86|IndexInSheet=5|OwnerPartId=-1|Location.X=256|Location.Y=934|Location.Y_Frac=48252|Color=8388608|FontID=2|IsHidden=T|Text=*|Name=SHEETPART
|RECORD=41|OwnerIndex=86|IndexInSheet=6|OwnerPartId=-1|Location.X=256|Location.Y=934|Location.Y_Frac=48252|Color=8388608|FontID=2|IsHidden=T|Text=10%|Name=P1
|RECORD=41|OwnerIndex=86|IndexInSheet=7|OwnerPartId=-1|Location.X=256|Location.Y=934|Location.Y_Frac=48252|Color=8388608|FontID=2|IsHidden=T|Text=85C|Name=MAXTEMP
|RECORD=41|OwnerIndex=86|IndexInSheet=8|OwnerPartId=-1|Location.X=256|Location.Y=934|Location.Y_Frac=48252|Color=8388608|FontID=2|IsHidden=T|Text=-55C|Name=MINTEMP
|RECORD=41|OwnerIndex=86|IndexInSheet=9|OwnerPartId=-1|Location.X=256|Location.Y=934|Location.Y_Frac=48252|Color=8388608|FontID=2|IsHidden=T|Name=OTHER
|RECORD=41|OwnerIndex=86|IndexInSheet=10|OwnerPartId=-1|Location.X=256|Location.Y=934|Location.Y_Frac=48252|Color=8388608|FontID=2|IsHidden=T|Text=25V|Name=P2
|RECORD=41|OwnerIndex=86|IndexInSheet=11|OwnerPartId=-1|Location.X=256|Location.Y=934|Location.Y_Frac=48252|Color=8388608|FontID=2|IsHidden=T|Text=X5R|Name=P3
|RECORD=41|OwnerIndex=86|IndexInSheet=12|OwnerPartId=-1|Location.X=256|Location.Y=934|Location.Y_Frac=48252|Color=8388608|FontID=2|IsHidden=T|Text=0805|Name=Size
|RECORD=41|OwnerIndex=86|IndexInSheet=13|OwnerPartId=-1|Location.X=256|Location.Y=934|Location.Y_Frac=48252|Color=8388608|FontID=2|IsHidden=T|Name=SUB
|RECORD=41|OwnerIndex=86|IndexInSheet=14|OwnerPartId=-1|Location.X=256|Location.Y=934|Location.Y_Frac=48252|Color=8388608|FontID=1|IsHidden=T|Text=CAP, CER, 10.UF, 10V, 10%, X5R, 0805|Name=DESC
|RECORD=41|OwnerIndex=86|IndexInSheet=15|OwnerPartId=-1|Location.X=256|Location.Y=933|Location.Y_Frac=98252|Color=8388608|FontID=1|IsHidden=T|Text=MOUSER|Name=Supplier 1|ReadOnlyState=1
|RECORD=41|OwnerIndex=86|IndexInSheet=16|OwnerPartId=-1|Location.X=256|Location.Y=933|Location.Y_Frac=98252|Color=8388608|FontID=1|IsHidden=T|Text=963-TMK212BBJ106KG-T|Name=Supplier Part Number 1|ReadOnlyState=1
|RECORD=41|OwnerIndex=86|IndexInSheet=17|OwnerPartId=-1|Location.X=280|Location.Y=890|Color=8388608|FontID=2|Text=10uF|Name=VALUE
|RECORD=2|OwnerIndex=86|OwnerPartId=1|FormalType=1|Electrical=4|PinConglomerate=35|PinLength=10|Location.X=270|Location.Y=890|Name=2|Designator=2|SwapIdPin=2|SwapIDPart=1|PinPropagationDelay=0.000000E+000
|RECORD=2|OwnerIndex=86|OwnerPartId=1|FormalType=1|Electrical=4|PinConglomerate=33|PinLength=10|Location.X=270|Location.Y=900|Name=1|Designator=1|SwapIdPin=1|SwapIDPart=1|PinPropagationDelay=0.000000E+000
|RECORD=13|OwnerIndex=86|IsNotAccesible=T|IndexInSheet=20|OwnerPartId=1|Location.X=270|Location.Y=892|Location.Y_Frac=50000|Corner.X=270|Corner.Y=890|LineWidth=1|Color=16711680
|RECORD=13|OwnerIndex=86|IsNotAccesible=T|IndexInSheet=21|OwnerPartId=1|Location.X=270|Location.Y=900|Corner.X=270|Corner.Y=897|Corner.Y_Frac=50000|LineWidth=1|Color=16711680
|RECORD=13|OwnerIndex=86|IsNotAccesible=T|IndexInSheet=22|OwnerPartId=1|Location.X=275|Location.Y=892|Location.Y_Frac=50000|Corner.X=265|Corner.Y=892|Corner.Y_Frac=50000|LineWidth=1|Color=16711680
|RECORD=13|OwnerIndex=86|IsNotAccesible=T|IndexInSheet=23|OwnerPartId=1|Location.X=275|Location.Y=897|Location.Y_Frac=50000|Corner.X=265|Corner.Y=897|Corner.Y_Frac=50000|LineWidth=1|Color=16711680
|RECORD=41|OwnerIndex=86|IndexInSheet=24|OwnerPartId=-1|Location.X=256|Location.Y=933|Location.Y_Frac=98951|Color=8388608|FontID=1|IsHidden=T|Text=<VALENTIUM>|Name=VALENTIUM PART NUM
|RECORD=34|OwnerIndex=86|IndexInSheet=-1|OwnerPartId=-1|Location.X=280|Location.Y=900|Color=8388608|FontID=3|Text=C60|Name=Designator|ReadOnlyState=1
|RECORD=41|OwnerIndex=86|IndexInSheet=-1|OwnerPartId=-1|Location.X=277|Location.X_Frac=50000|Location.Y=855|Color=8388608|FontID=2|IsHidden=T|Text=CAP_0805_10UF_25V|Name=Comment
|RECORD=44|OwnerIndex=86
|RECORD=45|OwnerIndex=116|IndexInSheet=-1|Description=Chip Capacitor, 0805, 2-Leads, Body 2.00x1.25mm, IPC Medium Density|UseComponentLibrary=T|ModelName=CAPC2012X14N|ModelType=PCBLIB|DatafileCount=1|ModelDatafileEntity0=CAPC2012X14N|ModelDatafileKind0=PCBLib|IsCurrent=T|DatalinksLocked=T|DatabaseDatalinksLocked=T|IntegratedModel=T|DatabaseModel=T
|RECORD=46|OwnerIndex=117
|RECORD=48|OwnerIndex=117
|RECORD=1|LibReference=RCB-F9T|ComponentDescription=MOD, GPS|PartCount=2|DisplayModeCount=1|IndexInSheet=43|OwnerPartId=-1|Location.X=590|Location.Y=920|CurrentPartId=1|LibraryPath=*|SourceLibraryName=Modules.IntLib|TargetFileName=*|AreaColor=11599871|Color=128|PartIDLocked=F|PinsMoveable=T|DesignItemId=RCB-F9T|AllPinCount=8
|RECORD=41|OwnerIndex=120|OwnerPartId=-1|Location.X=590|Location.Y=920|Color=8388608|FontID=2|IsHidden=T|Text=RCB-F9T|Name=MFG PART NUM
|RECORD=41|OwnerIndex=120|IndexInSheet=1|OwnerPartId=-1|Location.X=590|Location.Y=920|Color=8388608|FontID=2|IsHidden=T|Text=UBLOCKS|Name=MFG NAME
|RECORD=41|OwnerIndex=120|IndexInSheet=2|OwnerPartId=-1|Location.X=590|Location.Y=920|Color=8388608|FontID=2|IsHidden=T|Text=MOD|Name=CATEGORY
|RECORD=41|OwnerIndex=120|IndexInSheet=3|OwnerPartId=-1|Location.X=590|Location.Y=920|Color=8388608|FontID=2|IsHidden=T|Text=9/11/13|Name=MODIFY DATE
|RECORD=41|OwnerIndex=120|IndexInSheet=4|OwnerPartId=-1|Location.X=588|Location.Y=669|Color=8388608|FontID=1|IsHidden=T|Text=GPS|Name=P1
|RECORD=41|OwnerIndex=120|IndexInSheet=5|OwnerPartId=-1|Location.X=588|Location.Y=669|Color=8388608|FontID=1|IsHidden=T|Name=P2
|RECORD=41|OwnerIndex=120|IndexInSheet=6|OwnerPartId=-1|Location.X=588|Location.Y=669|Color=8388608|FontID=1|IsHidden=T|Name=P3
|RECORD=41|OwnerIndex=120|IndexInSheet=7|OwnerPartId=-1|Location.X=588|Location.Y=669|Color=8388608|FontID=1|IsHidden=T|Name=OTHER
|RECORD=41|OwnerIndex=120|IndexInSheet=8|OwnerPartId=-1|Location.X=588|Location.Y=669|Color=8388608|FontID=1|IsHidden=T|Name=DATE
|RECORD=41|OwnerIndex=120|IndexInSheet=9|OwnerPartId=-1|Location.X=588|Location.Y=669|Color=8388608|FontID=1|IsHidden=T|Text=*|Name=SHEETPART
|RECORD=41|OwnerIndex=120|IndexInSheet=10|OwnerPartId=-1|Location.X=588|Location.Y=669|Color=8388608|FontID=1|IsHidden=T|Name=SUB
|RECORD=41|OwnerIndex=120|IndexInSheet=11|OwnerPartId=-1|Location.X=588|Location.Y=669|Color=8388608|FontID=1|IsHidden=T|Name=SIZE
|RECORD=41|OwnerIndex=120|IndexInSheet=12|OwnerPartId=-1|Location.X=588|Location.Y=669|Color=8388608|FontID=1|IsHidden=T|Text=-40C|Name=MINTEMP
|RECORD=41|OwnerIndex=120|IndexInSheet=13|OwnerPartId=-1|Location.X=588|Location.Y=669|Color=8388608|FontID=1|IsHidden=T|Text=80C|Name=MAXTEMP
|RECORD=41|OwnerIndex=120|IndexInSheet=14|OwnerPartId=-1|Location.X=588|Location.Y=659|Color=8388608|FontID=1|IsHidden=T|Text=.|Name=DATE
|RECORD=41|OwnerIndex=120|IndexInSheet=15|OwnerPartId=-1|Location.X=588|Location.Y=974|Color=8388608|FontID=1|IsHidden=T|Text=MOD BLE 4.2|Name=DESC
|RECORD=41|OwnerIndex=120|IndexInSheet=16|OwnerPartId=-1|Location.X=558|Location.Y=992|Color=8388608|FontID=1|IsHidden=T|Text=<V PART NUM>|Name=VELENTIUM PART NUM
|RECORD=41|OwnerIndex=120|IndexInSheet=17|OwnerPartId=-1|Location.X=508|Location.Y=974|Color=8388608|FontID=1|IsHidden=T|Text=Digi-Key|Name=Supplier 1|ReadOnlyState=3
|RECORD=41|OwnerIndex=120|IndexInSheet=18|OwnerPartId=-1|Location.X=508|Location.Y=974|Color=8388608|FontID=1|IsHidden=T|Text=672-RCB-F9T-ND|Name=Supplier Part Number 1|ReadOnlyState=3
|RECORD=14|OwnerIndex=120|IsNotAccesible=T|IndexInSheet=19|OwnerPartId=1|Location.X=540|Location.Y=890|Corner.X=640|Corner.Y=940|Color=128|AreaColor=11599871|IsSolid=T
|RECORD=2|OwnerIndex=120|OwnerPartId=1|FormalType=1|Electrical=4|PinConglomerate=26|PinLength=30|Location.X=540|Location.Y=930|Name=VCC_ANT|Designator=1|SwapIDPart=Ž&Ž||PinPropagationDelay=0.000000E+000
|RECORD=2|OwnerIndex=120|OwnerPartId=1|FormalType=1|Electrical=4|PinConglomerate=26|PinLength=30|Location.X=540|Location.Y=920|Name=VCC|Designator=2|SwapIDPart=Ž&Ž||PinPropagationDelay=0.000000E+000
|RECORD=2|OwnerIndex=120|OwnerPartId=1|FormalType=1|Electrical=4|PinConglomerate=26|PinLength=30|Location.X=540|Location.Y=910|Name=TXD|Designator=3|SwapIDPart=Ž&Ž||PinPropagationDelay=0.000000E+000
|RECORD=2|OwnerIndex=120|OwnerPartId=1|FormalType=1|Electrical=4|PinConglomerate=26|PinLength=30|Location.X=540|Location.Y=900|Name=RST|Designator=4|SwapIDPart=Ž&Ž||PinPropagationDelay=0.000000E+000
|RECORD=2|OwnerIndex=120|OwnerPartId=1|FormalType=1|Electrical=4|PinConglomerate=24|PinLength=30|Location.X=640|Location.Y=900|Name=RXD|Designator=5|SwapIDPart=Ž&Ž||PinPropagationDelay=0.000000E+000
|RECORD=2|OwnerIndex=120|OwnerPartId=1|FormalType=1|Electrical=4|PinConglomerate=24|PinLength=30|Location.X=640|Location.Y=910|Name=TP1|Designator=6|SwapIDPart=Ž&Ž||PinPropagationDelay=0.000000E+000
|RECORD=2|OwnerIndex=120|OwnerPartId=1|FormalType=1|Electrical=4|PinConglomerate=24|PinLength=30|Location.X=640|Location.Y=920|Name=TP2|Designator=7|SwapIDPart=Ž&Ž||PinPropagationDelay=0.000000E+000
|RECORD=2|OwnerIndex=120|OwnerPartId=1|FormalType=1|Electrical=4|PinConglomerate=24|PinLength=30|Location.X=640|Location.Y=930|Name=GND|Designator=8|SwapIDPart=Ž&Ž||PinPropagationDelay=0.000000E+000
|RECORD=34|OwnerIndex=120|IndexInSheet=-1|OwnerPartId=-1|Location.X=540|Location.Y=940|Color=8388608|FontID=3|Text=U9|Name=Designator|ReadOnlyState=1
|RECORD=41|OwnerIndex=120|IndexInSheet=-1|OwnerPartId=-1|Location.X=540|Location.Y=878|Color=8388608|FontID=2|Text=RCB-F9T|Name=Comment
|RECORD=44|OwnerIndex=120
|RECORD=45|OwnerIndex=159|IndexInSheet=-1|UseComponentLibrary=T|ModelName=RCB-F9T|ModelType=PCBLIB|DatafileCount=1|ModelDatafileEntity0=RCB-F9T|ModelDatafileKind0=PCBLib|IsCurrent=T|DatalinksLocked=T|DatabaseDatalinksLocked=T|IntegratedModel=T|DatabaseModel=T
|RECORD=46|OwnerIndex=160
|RECORD=48|OwnerIndex=160
|RECORD=17|IndexInSheet=44|OwnerPartId=-1|ShowNetName=T|Location.X=270|Location.Y=770|Orientation=1|Color=128|FontID=1|Text=+5.0V
|RECORD=17|IndexInSheet=45|OwnerPartId=-1|Style=4|ShowNetName=T|Location.X=690|Location.Y=680|Orientation=3|Color=128|FontID=1|Text=GND
|RECORD=17|IndexInSheet=46|OwnerPartId=-1|ShowNetName=T|Location.X=170|Location.Y=770|Orientation=1|Color=128|FontID=1|Text=+3.3V
|RECORD=17|IndexInSheet=47|OwnerPartId=-1|Style=4|ShowNetName=T|Location.X=170|Location.Y=690|Orientation=3|Color=128|FontID=1|Text=GND
|RECORD=17|IndexInSheet=48|OwnerPartId=-1|Style=4|ShowNetName=T|Location.X=270|Location.Y=690|Orientation=3|Color=128|FontID=1|Text=GND
|RECORD=17|IndexInSheet=49|OwnerPartId=-1|ShowNetName=T|Location.X=760|Location.Y=740|Color=255|FontID=1|Text=GPS2_TP2|IsCrossSheetConnector=T
|RECORD=17|IndexInSheet=50|OwnerPartId=-1|ShowNetName=T|Location.X=760|Location.Y=730|Color=255|FontID=1|Text=GPS2_TP1|IsCrossSheetConnector=T
|RECORD=17|IndexInSheet=51|OwnerPartId=-1|ShowNetName=T|Location.X=760|Location.Y=720|Color=255|FontID=1|Text=GPS2_RX|IsCrossSheetConnector=T
|RECORD=17|IndexInSheet=52|OwnerPartId=-1|ShowNetName=T|Location.X=420|Location.Y=730|Orientation=2|Color=255|FontID=1|Text=GPS2_TX|IsCrossSheetConnector=T
|RECORD=17|IndexInSheet=53|OwnerPartId=-1|ShowNetName=T|Location.X=420|Location.Y=720|Orientation=2|Color=255|FontID=1|Text=GPS2_RST|IsCrossSheetConnector=T
|RECORD=1|LibReference=CAP_0805_10UF_25V|ComponentDescription=CAP, CER, 10.UF, 25V, 10%, X5R, 0805|PartCount=2|DisplayModeCount=1|IndexInSheet=54|OwnerPartId=-1|Location.X=150|Location.Y=680|CurrentPartId=1|LibraryPath=*|SourceLibraryName=Capacitors.IntLib|TargetFileName=*|AreaColor=11599871|Color=128|PartIDLocked=F|DesignItemId=CAP_0805_10UF_25V|AllPinCount=2
|RECORD=41|OwnerIndex=173|OwnerPartId=-1|Location.X=150|Location.Y=680|Color=8388608|FontID=2|IsHidden=T|Text=TAIYO YUDEN|Name=MFG NAME
|RECORD=41|OwnerIndex=173|IndexInSheet=1|OwnerPartId=-1|Location.X=150|Location.Y=680|Color=8388608|FontID=2|IsHidden=T|Text=TMK212BBJ106KG-T|Name=MFG PART NUM
|RECORD=41|OwnerIndex=173|IndexInSheet=2|OwnerPartId=-1|Location.X=150|Location.Y=680|Color=8388608|FontID=2|IsHidden=T|Text=10/23/2013|Name=MODIFY DATE
|RECORD=41|OwnerIndex=173|IndexInSheet=3|OwnerPartId=-1|Location.X=150|Location.Y=680|Color=8388608|FontID=2|IsHidden=T|Text=CAP, CER|Name=CATEGORY
|RECORD=41|OwnerIndex=173|IndexInSheet=4|OwnerPartId=-1|Location.X=148|Location.Y=692|Location.Y_Frac=50000|Color=8388608|FontID=2|IsHidden=T|Text=4/11/2006 3:37:28 PM|Name=Date
|RECORD=41|OwnerIndex=173|IndexInSheet=5|OwnerPartId=-1|Location.X=156|Location.Y=754|Location.Y_Frac=48252|Color=8388608|FontID=2|IsHidden=T|Text=*|Name=SHEETPART
|RECORD=41|OwnerIndex=173|IndexInSheet=6|OwnerPartId=-1|Location.X=156|Location.Y=754|Location.Y_Frac=48252|Color=8388608|FontID=2|IsHidden=T|Text=10%|Name=P1
|RECORD=41|OwnerIndex=173|IndexInSheet=7|OwnerPartId=-1|Location.X=156|Location.Y=754|Location.Y_Frac=48252|Color=8388608|FontID=2|IsHidden=T|Text=85C|Name=MAXTEMP
|RECORD=41|OwnerIndex=173|IndexInSheet=8|OwnerPartId=-1|Location.X=156|Location.Y=754|Location.Y_Frac=48252|Color=8388608|FontID=2|IsHidden=T|Text=-55C|Name=MINTEMP
|RECORD=41|OwnerIndex=173|IndexInSheet=9|OwnerPartId=-1|Location.X=156|Location.Y=754|Location.Y_Frac=48252|Color=8388608|FontID=2|IsHidden=T|Name=OTHER
|RECORD=41|OwnerIndex=173|IndexInSheet=10|OwnerPartId=-1|Location.X=156|Location.Y=754|Location.Y_Frac=48252|Color=8388608|FontID=2|IsHidden=T|Text=25V|Name=P2
|RECORD=41|OwnerIndex=173|IndexInSheet=11|OwnerPartId=-1|Location.X=156|Location.Y=754|Location.Y_Frac=48252|Color=8388608|FontID=2|IsHidden=T|Text=X5R|Name=P3
|RECORD=41|OwnerIndex=173|IndexInSheet=12|OwnerPartId=-1|Location.X=156|Location.Y=754|Location.Y_Frac=48252|Color=8388608|FontID=2|IsHidden=T|Text=0805|Name=Size
|RECORD=41|OwnerIndex=173|IndexInSheet=13|OwnerPartId=-1|Location.X=156|Location.Y=754|Location.Y_Frac=48252|Color=8388608|FontID=2|IsHidden=T|Name=SUB
|RECORD=41|OwnerIndex=173|IndexInSheet=14|OwnerPartId=-1|Location.X=156|Location.Y=754|Location.Y_Frac=48252|Color=8388608|FontID=1|IsHidden=T|Text=CAP, CER, 10.UF, 10V, 10%, X5R, 0805|Name=DESC
|RECORD=41|OwnerIndex=173|IndexInSheet=15|OwnerPartId=-1|Location.X=156|Location.Y=753|Location.Y_Frac=98252|Color=8388608|FontID=1|IsHidden=T|Text=MOUSER|Name=Supplier 1|ReadOnlyState=1
|RECORD=41|OwnerIndex=173|IndexInSheet=16|OwnerPartId=-1|Location.X=156|Location.Y=753|Location.Y_Frac=98252|Color=8388608|FontID=1|IsHidden=T|Text=963-TMK212BBJ106KG-T|Name=Supplier Part Number 1|ReadOnlyState=1
|RECORD=41|OwnerIndex=173|IndexInSheet=17|OwnerPartId=-1|Location.X=180|Location.Y=710|Color=8388608|FontID=2|Text=10uF|Name=VALUE
|RECORD=2|OwnerIndex=173|OwnerPartId=1|FormalType=1|Electrical=4|PinConglomerate=35|PinLength=10|Location.X=170|Location.Y=710|Name=2|Designator=2|SwapIdPin=2|SwapIDPart=1|PinPropagationDelay=0.000000E+000
|RECORD=2|OwnerIndex=173|OwnerPartId=1|FormalType=1|Electrical=4|PinConglomerate=33|PinLength=10|Location.X=170|Location.Y=720|Name=1|Designator=1|SwapIdPin=1|SwapIDPart=1|PinPropagationDelay=0.000000E+000
|RECORD=13|OwnerIndex=173|IsNotAccesible=T|IndexInSheet=20|OwnerPartId=1|Location.X=170|Location.Y=712|Location.Y_Frac=50000|Corner.X=170|Corner.Y=710|LineWidth=1|Color=16711680
|RECORD=13|OwnerIndex=173|IsNotAccesible=T|IndexInSheet=21|OwnerPartId=1|Location.X=170|Location.Y=720|Corner.X=170|Corner.Y=717|Corner.Y_Frac=50000|LineWidth=1|Color=16711680
|RECORD=13|OwnerIndex=173|IsNotAccesible=T|IndexInSheet=22|OwnerPartId=1|Location.X=175|Location.Y=712|Location.Y_Frac=50000|Corner.X=165|Corner.Y=712|Corner.Y_Frac=50000|LineWidth=1|Color=16711680
|RECORD=13|OwnerIndex=173|IsNotAccesible=T|IndexInSheet=23|OwnerPartId=1|Location.X=175|Location.Y=717|Location.Y_Frac=50000|Corner.X=165|Corner.Y=717|Corner.Y_Frac=50000|LineWidth=1|Color=16711680
|RECORD=41|OwnerIndex=173|IndexInSheet=24|OwnerPartId=-1|Location.X=156|Location.Y=753|Location.Y_Frac=98951|Color=8388608|FontID=1|IsHidden=T|Text=<VALENTIUM>|Name=VALENTIUM PART NUM
|RECORD=34|OwnerIndex=173|IndexInSheet=-1|OwnerPartId=-1|Location.X=180|Location.Y=720|Color=8388608|FontID=3|Text=C87|Name=Designator|ReadOnlyState=1
|RECORD=41|OwnerIndex=173|IndexInSheet=-1|OwnerPartId=-1|Location.X=177|Location.X_Frac=50000|Location.Y=675|Color=8388608|FontID=2|IsHidden=T|Text=CAP_0805_10UF_25V|Name=Comment
|RECORD=44|OwnerIndex=173
|RECORD=45|OwnerIndex=203|IndexInSheet=-1|Description=Chip Capacitor, 0805, 2-Leads, Body 2.00x1.25mm, IPC Medium Density|UseComponentLibrary=T|ModelName=CAPC2012X14N|ModelType=PCBLIB|DatafileCount=1|ModelDatafileEntity0=CAPC2012X14N|ModelDatafileKind0=PCBLib|IsCurrent=T|DatalinksLocked=T|DatabaseDatalinksLocked=T|IntegratedModel=T|DatabaseModel=T
|RECORD=46|OwnerIndex=204
|RECORD=48|OwnerIndex=204
|RECORD=1|LibReference=CAP_0805_10UF_25V|ComponentDescription=CAP, CER, 10.UF, 25V, 10%, X5R, 0805|PartCount=2|DisplayModeCount=1|IndexInSheet=55|OwnerPartId=-1|Location.X=250|Location.Y=680|CurrentPartId=1|LibraryPath=*|SourceLibraryName=Capacitors.IntLib|TargetFileName=*|AreaColor=11599871|Color=128|PartIDLocked=F|DesignItemId=CAP_0805_10UF_25V|AllPinCount=2
|RECORD=41|OwnerIndex=207|OwnerPartId=-1|Location.X=250|Location.Y=680|Color=8388608|FontID=2|IsHidden=T|Text=TAIYO YUDEN|Name=MFG NAME
|RECORD=41|OwnerIndex=207|IndexInSheet=1|OwnerPartId=-1|Location.X=250|Location.Y=680|Color=8388608|FontID=2|IsHidden=T|Text=TMK212BBJ106KG-T|Name=MFG PART NUM
|RECORD=41|OwnerIndex=207|IndexInSheet=2|OwnerPartId=-1|Location.X=250|Location.Y=680|Color=8388608|FontID=2|IsHidden=T|Text=10/23/2013|Name=MODIFY DATE
|RECORD=41|OwnerIndex=207|IndexInSheet=3|OwnerPartId=-1|Location.X=250|Location.Y=680|Color=8388608|FontID=2|IsHidden=T|Text=CAP, CER|Name=CATEGORY
|RECORD=41|OwnerIndex=207|IndexInSheet=4|OwnerPartId=-1|Location.X=248|Location.Y=692|Location.Y_Frac=50000|Color=8388608|FontID=2|IsHidden=T|Text=4/11/2006 3:37:28 PM|Name=Date
|RECORD=41|OwnerIndex=207|IndexInSheet=5|OwnerPartId=-1|Location.X=256|Location.Y=754|Location.Y_Frac=48252|Color=8388608|FontID=2|IsHidden=T|Text=*|Name=SHEETPART
|RECORD=41|OwnerIndex=207|IndexInSheet=6|OwnerPartId=-1|Location.X=256|Location.Y=754|Location.Y_Frac=48252|Color=8388608|FontID=2|IsHidden=T|Text=10%|Name=P1
|RECORD=41|OwnerIndex=207|IndexInSheet=7|OwnerPartId=-1|Location.X=256|Location.Y=754|Location.Y_Frac=48252|Color=8388608|FontID=2|IsHidden=T|Text=85C|Name=MAXTEMP
|RECORD=41|OwnerIndex=207|IndexInSheet=8|OwnerPartId=-1|Location.X=256|Location.Y=754|Location.Y_Frac=48252|Color=8388608|FontID=2|IsHidden=T|Text=-55C|Name=MINTEMP
|RECORD=41|OwnerIndex=207|IndexInSheet=9|OwnerPartId=-1|Location.X=256|Location.Y=754|Location.Y_Frac=48252|Color=8388608|FontID=2|IsHidden=T|Name=OTHER
|RECORD=41|OwnerIndex=207|IndexInSheet=10|OwnerPartId=-1|Location.X=256|Location.Y=754|Location.Y_Frac=48252|Color=8388608|FontID=2|IsHidden=T|Text=25V|Name=P2
|RECORD=41|OwnerIndex=207|IndexInSheet=11|OwnerPartId=-1|Location.X=256|Location.Y=754|Location.Y_Frac=48252|Color=8388608|FontID=2|IsHidden=T|Text=X5R|Name=P3
|RECORD=41|OwnerIndex=207|IndexInSheet=12|OwnerPartId=-1|Location.X=256|Location.Y=754|Location.Y_Frac=48252|Color=8388608|FontID=2|IsHidden=T|Text=0805|Name=Size
|RECORD=41|OwnerIndex=207|IndexInSheet=13|OwnerPartId=-1|Location.X=256|Location.Y=754|Location.Y_Frac=48252|Color=8388608|FontID=2|IsHidden=T|Name=SUB
|RECORD=41|OwnerIndex=207|IndexInSheet=14|OwnerPartId=-1|Location.X=256|Location.Y=754|Location.Y_Frac=48252|Color=8388608|FontID=1|IsHidden=T|Text=CAP, CER, 10.UF, 10V, 10%, X5R, 0805|Name=DESC
|RECORD=41|OwnerIndex=207|IndexInSheet=15|OwnerPartId=-1|Location.X=256|Location.Y=753|Location.Y_Frac=98252|Color=8388608|FontID=1|IsHidden=T|Text=MOUSER|Name=Supplier 1|ReadOnlyState=1
|RECORD=41|OwnerIndex=207|IndexInSheet=16|OwnerPartId=-1|Location.X=256|Location.Y=753|Location.Y_Frac=98252|Color=8388608|FontID=1|IsHidden=T|Text=963-TMK212BBJ106KG-T|Name=Supplier Part Number 1|ReadOnlyState=1
|RECORD=41|OwnerIndex=207|IndexInSheet=17|OwnerPartId=-1|Location.X=280|Location.Y=710|Color=8388608|FontID=2|Text=10uF|Name=VALUE
|RECORD=2|OwnerIndex=207|OwnerPartId=1|FormalType=1|Electrical=4|PinConglomerate=35|PinLength=10|Location.X=270|Location.Y=710|Name=2|Designator=2|SwapIdPin=2|SwapIDPart=1|PinPropagationDelay=0.000000E+000
|RECORD=2|OwnerIndex=207|OwnerPartId=1|FormalType=1|Electrical=4|PinConglomerate=33|PinLength=10|Location.X=270|Location.Y=720|Name=1|Designator=1|SwapIdPin=1|SwapIDPart=1|PinPropagationDelay=0.000000E+000
|RECORD=13|OwnerIndex=207|IsNotAccesible=T|IndexInSheet=20|OwnerPartId=1|Location.X=270|Location.Y=712|Location.Y_Frac=50000|Corner.X=270|Corner.Y=710|LineWidth=1|Color=16711680
|RECORD=13|OwnerIndex=207|IsNotAccesible=T|IndexInSheet=21|OwnerPartId=1|Location.X=270|Location.Y=720|Corner.X=270|Corner.Y=717|Corner.Y_Frac=50000|LineWidth=1|Color=16711680
|RECORD=13|OwnerIndex=207|IsNotAccesible=T|IndexInSheet=22|OwnerPartId=1|Location.X=275|Location.Y=712|Location.Y_Frac=50000|Corner.X=265|Corner.Y=712|Corner.Y_Frac=50000|LineWidth=1|Color=16711680
|RECORD=13|OwnerIndex=207|IsNotAccesible=T|IndexInSheet=23|OwnerPartId=1|Location.X=275|Location.Y=717|Location.Y_Frac=50000|Corner.X=265|Corner.Y=717|Corner.Y_Frac=50000|LineWidth=1|Color=16711680
|RECORD=41|OwnerIndex=207|IndexInSheet=24|OwnerPartId=-1|Location.X=256|Location.Y=753|Location.Y_Frac=98951|Color=8388608|FontID=1|IsHidden=T|Text=<VALENTIUM>|Name=VALENTIUM PART NUM
|RECORD=34|OwnerIndex=207|IndexInSheet=-1|OwnerPartId=-1|Location.X=280|Location.Y=720|Color=8388608|FontID=3|Text=C89|Name=Designator|ReadOnlyState=1
|RECORD=41|OwnerIndex=207|IndexInSheet=-1|OwnerPartId=-1|Location.X=277|Location.X_Frac=50000|Location.Y=675|Color=8388608|FontID=2|IsHidden=T|Text=CAP_0805_10UF_25V|Name=Comment
|RECORD=44|OwnerIndex=207
|RECORD=45|OwnerIndex=237|IndexInSheet=-1|Description=Chip Capacitor, 0805, 2-Leads, Body 2.00x1.25mm, IPC Medium Density|UseComponentLibrary=T|ModelName=CAPC2012X14N|ModelType=PCBLIB|DatafileCount=1|ModelDatafileEntity0=CAPC2012X14N|ModelDatafileKind0=PCBLib|IsCurrent=T|DatalinksLocked=T|DatabaseDatalinksLocked=T|IntegratedModel=T|DatabaseModel=T
|RECORD=46|OwnerIndex=238
|RECORD=48|OwnerIndex=238
|RECORD=1|LibReference=RCB-F9T|ComponentDescription=MOD, GPS|PartCount=2|DisplayModeCount=1|IndexInSheet=56|OwnerPartId=-1|Location.X=590|Location.Y=740|CurrentPartId=1|LibraryPath=*|SourceLibraryName=Modules.IntLib|TargetFileName=*|AreaColor=11599871|Color=128|PartIDLocked=F|PinsMoveable=T|DesignItemId=RCB-F9T|AllPinCount=8
|RECORD=41|OwnerIndex=241|OwnerPartId=-1|Location.X=590|Location.Y=740|Color=8388608|FontID=2|IsHidden=T|Text=RCB-F9T|Name=MFG PART NUM
|RECORD=41|OwnerIndex=241|IndexInSheet=1|OwnerPartId=-1|Location.X=590|Location.Y=740|Color=8388608|FontID=2|IsHidden=T|Text=UBLOCKS|Name=MFG NAME
|RECORD=41|OwnerIndex=241|IndexInSheet=2|OwnerPartId=-1|Location.X=590|Location.Y=740|Color=8388608|FontID=2|IsHidden=T|Text=MOD|Name=CATEGORY
|RECORD=41|OwnerIndex=241|IndexInSheet=3|OwnerPartId=-1|Location.X=590|Location.Y=740|Color=8388608|FontID=2|IsHidden=T|Text=9/11/13|Name=MODIFY DATE
|RECORD=41|OwnerIndex=241|IndexInSheet=4|OwnerPartId=-1|Location.X=588|Location.Y=489|Color=8388608|FontID=1|IsHidden=T|Text=GPS|Name=P1
|RECORD=41|OwnerIndex=241|IndexInSheet=5|OwnerPartId=-1|Location.X=588|Location.Y=489|Color=8388608|FontID=1|IsHidden=T|Name=P2
|RECORD=41|OwnerIndex=241|IndexInSheet=6|OwnerPartId=-1|Location.X=588|Location.Y=489|Color=8388608|FontID=1|IsHidden=T|Name=P3
|RECORD=41|OwnerIndex=241|IndexInSheet=7|OwnerPartId=-1|Location.X=588|Location.Y=489|Color=8388608|FontID=1|IsHidden=T|Name=OTHER
|RECORD=41|OwnerIndex=241|IndexInSheet=8|OwnerPartId=-1|Location.X=588|Location.Y=489|Color=8388608|FontID=1|IsHidden=T|Name=DATE
|RECORD=41|OwnerIndex=241|IndexInSheet=9|OwnerPartId=-1|Location.X=588|Location.Y=489|Color=8388608|FontID=1|IsHidden=T|Text=*|Name=SHEETPART
|RECORD=41|OwnerIndex=241|IndexInSheet=10|OwnerPartId=-1|Location.X=588|Location.Y=489|Color=8388608|FontID=1|IsHidden=T|Name=SUB
|RECORD=41|OwnerIndex=241|IndexInSheet=11|OwnerPartId=-1|Location.X=588|Location.Y=489|Color=8388608|FontID=1|IsHidden=T|Name=SIZE
|RECORD=41|OwnerIndex=241|IndexInSheet=12|OwnerPartId=-1|Location.X=588|Location.Y=489|Color=8388608|FontID=1|IsHidden=T|Text=-40C|Name=MINTEMP
|RECORD=41|OwnerIndex=241|IndexInSheet=13|OwnerPartId=-1|Location.X=588|Location.Y=489|Color=8388608|FontID=1|IsHidden=T|Text=80C|Name=MAXTEMP
|RECORD=41|OwnerIndex=241|IndexInSheet=14|OwnerPartId=-1|Location.X=588|Location.Y=479|Color=8388608|FontID=1|IsHidden=T|Text=.|Name=DATE
|RECORD=41|OwnerIndex=241|IndexInSheet=15|OwnerPartId=-1|Location.X=588|Location.Y=794|Color=8388608|FontID=1|IsHidden=T|Text=MOD BLE 4.2|Name=DESC
|RECORD=41|OwnerIndex=241|IndexInSheet=16|OwnerPartId=-1|Location.X=558|Location.Y=812|Color=8388608|FontID=1|IsHidden=T|Text=<V PART NUM>|Name=VELENTIUM PART NUM
|RECORD=41|OwnerIndex=241|IndexInSheet=17|OwnerPartId=-1|Location.X=508|Location.Y=794|Color=8388608|FontID=1|IsHidden=T|Text=Digi-Key|Name=Supplier 1|ReadOnlyState=3
|RECORD=41|OwnerIndex=241|IndexInSheet=18|OwnerPartId=-1|Location.X=508|Location.Y=794|Color=8388608|FontID=1|IsHidden=T|Text=672-RCB-F9T-ND|Name=Supplier Part Number 1|ReadOnlyState=3
|RECORD=14|OwnerIndex=241|IsNotAccesible=T|IndexInSheet=19|OwnerPartId=1|Location.X=540|Location.Y=710|Corner.X=640|Corner.Y=760|Color=128|AreaColor=11599871|IsSolid=T
|RECORD=2|OwnerIndex=241|OwnerPartId=1|FormalType=1|Electrical=4|PinConglomerate=26|PinLength=30|Location.X=540|Location.Y=750|Name=VCC_ANT|Designator=1|SwapIDPart=Ž&Ž||PinPropagationDelay=0.000000E+000
|RECORD=2|OwnerIndex=241|OwnerPartId=1|FormalType=1|Electrical=4|PinConglomerate=26|PinLength=30|Location.X=540|Location.Y=740|Name=VCC|Designator=2|SwapIDPart=Ž&Ž||PinPropagationDelay=0.000000E+000
|RECORD=2|OwnerIndex=241|OwnerPartId=1|FormalType=1|Electrical=4|PinConglomerate=26|PinLength=30|Location.X=540|Location.Y=730|Name=TXD|Designator=3|SwapIDPart=Ž&Ž||PinPropagationDelay=0.000000E+000
|RECORD=2|OwnerIndex=241|OwnerPartId=1|FormalType=1|Electrical=4|PinConglomerate=26|PinLength=30|Location.X=540|Location.Y=720|Name=RST|Designator=4|SwapIDPart=Ž&Ž||PinPropagationDelay=0.000000E+000
|RECORD=2|OwnerIndex=241|OwnerPartId=1|FormalType=1|Electrical=4|PinConglomerate=24|PinLength=30|Location.X=640|Location.Y=720|Name=RXD|Designator=5|SwapIDPart=Ž&Ž||PinPropagationDelay=0.000000E+000
|RECORD=2|OwnerIndex=241|OwnerPartId=1|FormalType=1|Electrical=4|PinConglomerate=24|PinLength=30|Location.X=640|Location.Y=730|Name=TP1|Designator=6|SwapIDPart=Ž&Ž||PinPropagationDelay=0.000000E+000
|RECORD=2|OwnerIndex=241|OwnerPartId=1|FormalType=1|Electrical=4|PinConglomerate=24|PinLength=30|Location.X=640|Location.Y=740|Name=TP2|Designator=7|SwapIDPart=Ž&Ž||PinPropagationDelay=0.000000E+000
|RECORD=2|OwnerIndex=241|OwnerPartId=1|FormalType=1|Electrical=4|PinConglomerate=24|PinLength=30|Location.X=640|Location.Y=750|Name=GND|Designator=8|SwapIDPart=Ž&Ž||PinPropagationDelay=0.000000E+000
|RECORD=34|OwnerIndex=241|IndexInSheet=-1|OwnerPartId=-1|Location.X=540|Location.Y=760|Color=8388608|FontID=3|Text=U14|Name=Designator|ReadOnlyState=1
|RECORD=41|OwnerIndex=241|IndexInSheet=-1|OwnerPartId=-1|Location.X=540|Location.Y=698|Color=8388608|FontID=2|Text=RCB-F9T|Name=Comment
|RECORD=44|OwnerIndex=241
|RECORD=45|OwnerIndex=280|IndexInSheet=-1|UseComponentLibrary=T|ModelName=RCB-F9T|ModelType=PCBLIB|DatafileCount=1|ModelDatafileEntity0=RCB-F9T|ModelDatafileKind0=PCBLib|IsCurrent=T|DatalinksLocked=T|DatabaseDatalinksLocked=T|IntegratedModel=T|DatabaseModel=T
|RECORD=46|OwnerIndex=281
|RECORD=48|OwnerIndex=281
|RECORD=22|IndexInSheet=57|OwnerPartId=-1|Location.X=1450|Location.Y=770|Color=255|Orientation=1|Symbol=Thin Cross|IsActive=T|SuppressAll=T
|RECORD=17|IndexInSheet=58|OwnerPartId=-1|Style=4|ShowNetName=T|Location.X=1430|Location.Y=890|Orientation=3|Color=128|FontID=1|Text=GND
|RECORD=1|LibReference=CAP_0805_1UF_25V|ComponentDescription=CAP, CER, 1.0UF, 25V, 10%, X5R, 0805|PartCount=2|DisplayModeCount=1|IndexInSheet=59|OwnerPartId=-1|Location.X=1410|Location.Y=950|Orientation=2|CurrentPartId=1|LibraryPath=*|SourceLibraryName=Capacitors.IntLib|TargetFileName=*|AreaColor=11599871|Color=128|PartIDLocked=F|DesignItemId=CAP_0805_1UF_25V|AllPinCount=2
|RECORD=41|OwnerIndex=286|OwnerPartId=-1|Location.X=1384|Location.Y=932|Color=8388608|FontID=2|IsHidden=T|Text=AVX|Name=MFG NAME
|RECORD=41|OwnerIndex=286|IndexInSheet=1|OwnerPartId=-1|Location.X=1384|Location.Y=932|Color=8388608|FontID=2|IsHidden=T|Text=08053D105KAT2A|Name=MFG PART NUM
|RECORD=41|OwnerIndex=286|IndexInSheet=2|OwnerPartId=-1|Location.X=1384|Location.Y=932|Color=8388608|FontID=2|IsHidden=T|Text=10/23/2013|Name=MODIFY DATE
|RECORD=41|OwnerIndex=286|IndexInSheet=3|OwnerPartId=-1|Location.X=1384|Location.Y=932|Color=8388608|FontID=2|IsHidden=T|Text=CAP, CER|Name=CATEGORY
|RECORD=41|OwnerIndex=286|IndexInSheet=4|OwnerPartId=-1|Location.X=1384|Location.Y=932|Color=8388608|FontID=2|IsHidden=T|Text=4/11/2006 3:37:28 PM|Name=Date
|RECORD=41|OwnerIndex=286|IndexInSheet=5|OwnerPartId=-1|Location.X=1384|Location.Y=932|Color=8388608|FontID=2|IsHidden=T|Text=*|Name=SHEETPART
|RECORD=41|OwnerIndex=286|IndexInSheet=6|OwnerPartId=-1|Location.X=1384|Location.Y=932|Color=8388608|FontID=2|IsHidden=T|Text=10%|Name=P1
|RECORD=41|OwnerIndex=286|IndexInSheet=7|OwnerPartId=-1|Location.X=1384|Location.Y=932|Color=8388608|FontID=2|IsHidden=T|Text=85C|Name=MAXTEMP
|RECORD=41|OwnerIndex=286|IndexInSheet=8|OwnerPartId=-1|Location.X=1384|Location.Y=932|Color=8388608|FontID=2|IsHidden=T|Text=-55C|Name=MINTEMP
|RECORD=41|OwnerIndex=286|IndexInSheet=9|OwnerPartId=-1|Location.X=1384|Location.Y=932|Color=8388608|FontID=2|IsHidden=T|Name=OTHER
|RECORD=41|OwnerIndex=286|IndexInSheet=10|OwnerPartId=-1|Location.X=1384|Location.Y=932|Color=8388608|FontID=2|IsHidden=T|Text=25V|Name=P2
|RECORD=41|OwnerIndex=286|IndexInSheet=11|OwnerPartId=-1|Location.X=1384|Location.Y=932|Color=8388608|FontID=2|IsHidden=T|Text=X5R|Name=P3
|RECORD=41|OwnerIndex=286|IndexInSheet=12|OwnerPartId=-1|Location.X=1384|Location.Y=932|Color=8388608|FontID=2|IsHidden=T|Text=0805|Name=Size
|RECORD=41|OwnerIndex=286|IndexInSheet=13|OwnerPartId=-1|Location.X=1384|Location.Y=932|Color=8388608|FontID=2|IsHidden=T|Name=SUB
|RECORD=41|OwnerIndex=286|IndexInSheet=14|OwnerPartId=-1|Location.X=1384|Location.Y=932|Color=8388608|FontID=2|IsHidden=T|Text=Digi-Key|Name=Supplier 1|ReadOnlyState=3
|RECORD=41|OwnerIndex=286|IndexInSheet=15|OwnerPartId=-1|Location.X=1384|Location.Y=932|Color=8388608|FontID=2|IsHidden=T|Text=478-1409-1-ND|Name=Supplier Part Number 1|ReadOnlyState=3
|RECORD=41|OwnerIndex=286|IndexInSheet=16|OwnerPartId=-1|Location.X=1384|Location.Y=932|Color=8388608|FontID=1|IsHidden=T|Text=CAP, CER, 1.0UF, 25V, 10%, X5R, 0805|Name=DESC
|RECORD=41|OwnerIndex=286|IndexInSheet=17|OwnerPartId=-1|Location.X=1396|Location.Y=895|Color=8388608|FontID=2|Text=1.0UF|Name=VALUE
|RECORD=2|OwnerIndex=286|OwnerPartId=1|FormalType=1|Electrical=4|PinConglomerate=33|PinLength=10|Location.X=1390|Location.Y=920|Name=2|Designator=2|SwapIdPin=2|SwapIDPart=1|PinPropagationDelay=0.000000E+000
|RECORD=2|OwnerIndex=286|OwnerPartId=1|FormalType=1|Electrical=4|PinConglomerate=35|PinLength=10|Location.X=1390|Location.Y=910|Name=1|Designator=1|SwapIdPin=1|SwapIDPart=1|PinPropagationDelay=0.000000E+000
|RECORD=13|OwnerIndex=286|IsNotAccesible=T|IndexInSheet=20|OwnerPartId=1|Location.X=1390|Location.Y=917|Location.Y_Frac=50000|Corner.X=1390|Corner.Y=920|LineWidth=1|Color=16711680
|RECORD=13|OwnerIndex=286|IsNotAccesible=T|IndexInSheet=21|OwnerPartId=1|Location.X=1390|Location.Y=910|Corner.X=1390|Corner.Y=912|Corner.Y_Frac=50000|LineWidth=1|Color=16711680
|RECORD=13|OwnerIndex=286|IsNotAccesible=T|IndexInSheet=22|OwnerPartId=1|Location.X=1385|Location.Y=917|Location.Y_Frac=50000|Corner.X=1395|Corner.Y=917|Corner.Y_Frac=50000|LineWidth=1|Color=16711680
|RECORD=13|OwnerIndex=286|IsNotAccesible=T|IndexInSheet=23|OwnerPartId=1|Location.X=1385|Location.Y=912|Location.Y_Frac=50000|Corner.X=1395|Corner.Y=912|Corner.Y_Frac=50000|LineWidth=1|Color=16711680
|RECORD=41|OwnerIndex=286|IndexInSheet=24|OwnerPartId=-1|Location.X=1384|Location.Y=932|Color=8388608|FontID=1|IsHidden=T|Text=<VALENTIUM>|Name=VALENTIUM PART NUM
|RECORD=34|OwnerIndex=286|IndexInSheet=-1|OwnerPartId=-1|Location.X=1396|Location.Y=907|Color=8388608|FontID=3|Text=C91|Name=Designator|ReadOnlyState=1
|RECORD=41|OwnerIndex=286|IndexInSheet=-1|OwnerPartId=-1|Location.X=1384|Location.Y=932|Color=8388608|FontID=2|IsHidden=T|Text=CAP_0805_1UF_25V|Name=Comment
|RECORD=44|OwnerIndex=286
|RECORD=45|OwnerIndex=316|IndexInSheet=-1|Description=Chip Capacitor, 0805, 2-Leads, Body 2.00x1.25mm, IPC Medium Density|UseComponentLibrary=T|ModelName=CAPC2012X14N|ModelType=PCBLIB|DatafileCount=1|ModelDatafileEntity0=CAPC2012X14N|ModelDatafileKind0=PCBLib|IsCurrent=T|DatalinksLocked=T|DatabaseDatalinksLocked=T|IntegratedModel=T|DatabaseModel=T
|RECORD=46|OwnerIndex=317
|RECORD=48|OwnerIndex=317
|RECORD=1|LibReference=CAP_0603_10UF_25V|ComponentDescription=CAP, CER, 10.UF, 25V, 20%, X5R, AEC-Q200, 0603|PartCount=2|DisplayModeCount=1|IndexInSheet=60|OwnerPartId=-1|Location.X=1450|Location.Y=950|Orientation=2|CurrentPartId=1|LibraryPath=*|SourceLibraryName=Capacitors.IntLib|TargetFileName=*|AreaColor=11599871|Color=128|PartIDLocked=F|DesignItemId=CAP_0603_10UF_25V|AllPinCount=2
|RECORD=41|OwnerIndex=320|OwnerPartId=-1|Location.X=1424|Location.Y=932|Color=8388608|FontID=2|IsHidden=T|Text=CAP, CER|Name=CATEGORY
|RECORD=41|OwnerIndex=320|IndexInSheet=1|OwnerPartId=-1|Location.X=1424|Location.Y=932|Color=8388608|FontID=2|IsHidden=T|Text=MURATA|Name=MFG NAME
|RECORD=41|OwnerIndex=320|IndexInSheet=2|OwnerPartId=-1|Location.X=1424|Location.Y=932|Color=8388608|FontID=2|IsHidden=T|Text=GRT188R61E106ME13D|Name=MFG PART NUM
|RECORD=41|OwnerIndex=320|IndexInSheet=3|OwnerPartId=-1|Location.X=1424|Location.Y=932|Color=8388608|FontID=2|IsHidden=T|Text=10/23/2013|Name=MODIFY DATE
|RECORD=41|OwnerIndex=320|IndexInSheet=4|OwnerPartId=-1|Location.X=1424|Location.Y=932|Color=8388608|FontID=2|IsHidden=T|Text=7/25/2013|Name=Date
|RECORD=41|OwnerIndex=320|IndexInSheet=5|OwnerPartId=-1|Location.X=1424|Location.Y=932|Color=8388608|FontID=2|IsHidden=T|Text=*|Name=SHEETPART
|RECORD=41|OwnerIndex=320|IndexInSheet=6|OwnerPartId=-1|Location.X=1424|Location.Y=932|Color=8388608|FontID=2|IsHidden=T|Text=20%|Name=P1
|RECORD=41|OwnerIndex=320|IndexInSheet=7|OwnerPartId=-1|Location.X=1424|Location.Y=932|Color=8388608|FontID=2|IsHidden=T|Text=85C|Name=MAXTEMP
|RECORD=41|OwnerIndex=320|IndexInSheet=8|OwnerPartId=-1|Location.X=1424|Location.Y=932|Color=8388608|FontID=2|IsHidden=T|Text=-55C|Name=MINTEMP
|RECORD=41|OwnerIndex=320|IndexInSheet=9|OwnerPartId=-1|Location.X=1424|Location.Y=932|Color=8388608|FontID=2|IsHidden=T|Text=AEC-Q200|Name=OTHER
|RECORD=41|OwnerIndex=320|IndexInSheet=10|OwnerPartId=-1|Location.X=1424|Location.Y=932|Color=8388608|FontID=2|IsHidden=T|Text=25V|Name=P2
|RECORD=41|OwnerIndex=320|IndexInSheet=11|OwnerPartId=-1|Location.X=1424|Location.Y=932|Color=8388608|FontID=2|IsHidden=T|Text=X5R|Name=P3
|RECORD=41|OwnerIndex=320|IndexInSheet=12|OwnerPartId=-1|Location.X=1424|Location.Y=932|Color=8388608|FontID=2|IsHidden=T|Text=0603|Name=Size
|RECORD=41|OwnerIndex=320|IndexInSheet=13|OwnerPartId=-1|Location.X=1424|Location.Y=932|Color=8388608|FontID=2|IsHidden=T|Name=SUB
|RECORD=41|OwnerIndex=320|IndexInSheet=14|OwnerPartId=-1|Location.X=1424|Location.Y=932|Color=8388608|FontID=1|IsHidden=T|Text=CAP, CER, 10.UF, 25V, 20%, X5R, AEC-Q200, 0603|Name=DESC
|RECORD=41|OwnerIndex=320|IndexInSheet=15|OwnerPartId=-1|Location.X=1424|Location.Y=932|Color=8388608|FontID=1|IsHidden=T|Text=Digi-Key|Name=Supplier 1|ReadOnlyState=3
|RECORD=41|OwnerIndex=320|IndexInSheet=16|OwnerPartId=-1|Location.X=1424|Location.Y=932|Color=8388608|FontID=1|IsHidden=T|Text=490-12323-6-ND|Name=Supplier Part Number 1|ReadOnlyState=3
|RECORD=41|OwnerIndex=320|IndexInSheet=17|OwnerPartId=-1|Location.X=1424|Location.Y=932|Color=8388608|FontID=1|IsHidden=T|Text=<VALENTIUM>|Name=VALENTIUM PART NUM
|RECORD=41|OwnerIndex=320|IndexInSheet=18|OwnerPartId=-1|Location.X=1436|Location.Y=895|Color=8388608|FontID=2|Text=10.UF|Name=VALUE
|RECORD=2|OwnerIndex=320|OwnerPartId=1|FormalType=1|Electrical=4|PinConglomerate=33|PinLength=10|Location.X=1430|Location.Y=920|Name=2|Designator=2|SwapIdPin=2|SwapIDPart=1|PinPropagationDelay=0.000000E+000
|RECORD=2|OwnerIndex=320|OwnerPartId=1|FormalType=1|Electrical=4|PinConglomerate=35|PinLength=10|Location.X=1430|Location.Y=910|Name=1|Designator=1|SwapIdPin=1|SwapIDPart=1|PinPropagationDelay=0.000000E+000
|RECORD=13|OwnerIndex=320|IsNotAccesible=T|IndexInSheet=21|OwnerPartId=1|Location.X=1430|Location.Y=917|Location.Y_Frac=50000|Corner.X=1430|Corner.Y=920|LineWidth=1|Color=16711680
|RECORD=13|OwnerIndex=320|IsNotAccesible=T|IndexInSheet=22|OwnerPartId=1|Location.X=1430|Location.Y=910|Corner.X=1430|Corner.Y=912|Corner.Y_Frac=50000|LineWidth=1|Color=16711680
|RECORD=13|OwnerIndex=320|IsNotAccesible=T|IndexInSheet=23|OwnerPartId=1|Location.X=1425|Location.Y=917|Location.Y_Frac=50000|Corner.X=1435|Corner.Y=917|Corner.Y_Frac=50000|LineWidth=1|Color=16711680
|RECORD=13|OwnerIndex=320|IsNotAccesible=T|IndexInSheet=24|OwnerPartId=1|Location.X=1425|Location.Y=912|Location.Y_Frac=50000|Corner.X=1435|Corner.Y=912|Corner.Y_Frac=50000|LineWidth=1|Color=16711680
|RECORD=34|OwnerIndex=320|IndexInSheet=-1|OwnerPartId=-1|Location.X=1436|Location.Y=907|Color=8388608|FontID=3|Text=C92|Name=Designator|ReadOnlyState=1
|RECORD=41|OwnerIndex=320|IndexInSheet=-1|OwnerPartId=-1|Location.X=1424|Location.Y=932|Color=8388608|FontID=2|IsHidden=T|Text=="MFG PART NUM"|Name=Comment|ReadOnlyState=1
|RECORD=44|OwnerIndex=320
|RECORD=45|OwnerIndex=350|IndexInSheet=-1|Description=Chip Capacitor, 0603, 2-Leads, Body 1.60x0.80mm, IPC Medium Density|UseComponentLibrary=T|ModelName=CAPC1608X10N|ModelType=PCBLIB|DatafileCount=1|ModelDatafileEntity0=CAPC1608X10N|ModelDatafileKind0=PCBLib|IsCurrent=T|DatalinksLocked=T|DatabaseDatalinksLocked=T|IntegratedModel=T|DatabaseModel=T
|RECORD=46|OwnerIndex=351
|RECORD=48|OwnerIndex=351
|RECORD=17|IndexInSheet=61|OwnerPartId=-1|Style=4|ShowNetName=T|Location.X=1440|Location.Y=750|Orientation=3|Color=128|FontID=1|Text=GND
|RECORD=1|LibReference=RES_0603_10K|ComponentDescription=RES, 10K, 1%, 1/10W, TF, 0603|PartCount=2|DisplayModeCount=1|IndexInSheet=62|OwnerPartId=-1|Location.X=1370|Location.Y=750|Orientation=2|CurrentPartId=1|LibraryPath=*|SourceLibraryName=Resistors.IntLib|TargetFileName=*|AreaColor=11599871|Color=128|PartIDLocked=F|DesignItemId=RES_0603_10K|AllPinCount=2
|RECORD=41|OwnerIndex=355|OwnerPartId=-1|Location.X=1318|Location.Y=754|Color=8388608|FontID=2|IsHidden=T|Text=7/25/2013|Name=ModifyDate
|RECORD=41|OwnerIndex=355|IndexInSheet=1|OwnerPartId=-1|Location.X=1318|Location.Y=754|Color=8388608|FontID=2|IsHidden=T|Text=ERJ-3EKF1002V|Name=MFG PART NUM
|RECORD=41|OwnerIndex=355|IndexInSheet=2|OwnerPartId=-1|Location.X=1318|Location.Y=754|Color=8388608|FontID=2|IsHidden=T|Text=PANASONIC|Name=MFG NAME
|RECORD=41|OwnerIndex=355|IndexInSheet=3|OwnerPartId=-1|Location.X=1318|Location.Y=754|Color=8388608|FontID=2|IsHidden=T|Text=RES|Name=CATEGORY
|RECORD=41|OwnerIndex=355|IndexInSheet=4|OwnerPartId=-1|Location.X=1318|Location.Y=754|Color=8388608|FontID=2|IsHidden=T|Text=7/26/2013|Name=Date
|RECORD=41|OwnerIndex=355|IndexInSheet=5|OwnerPartId=-1|Location.X=1318|Location.Y=754|Color=8388608|FontID=2|IsHidden=T|Text=1%|Name=P1
|RECORD=41|OwnerIndex=355|IndexInSheet=6|OwnerPartId=-1|Location.X=1318|Location.Y=754|Color=8388608|FontID=2|IsHidden=T|Text=TF|Name=P3
|RECORD=41|OwnerIndex=355|IndexInSheet=7|OwnerPartId=-1|Location.X=1318|Location.Y=754|Color=8388608|FontID=2|IsHidden=T|Text=1/10W|Name=P2
|RECORD=41|OwnerIndex=355|IndexInSheet=8|OwnerPartId=-1|Location.X=1318|Location.Y=754|Color=8388608|FontID=2|IsHidden=T|Text=125C|Name=MAXTEMP
|RECORD=41|OwnerIndex=355|IndexInSheet=9|OwnerPartId=-1|Location.X=1318|Location.Y=754|Color=8388608|FontID=2|IsHidden=T|Text=-55C|Name=MINTEMP
|RECORD=41|OwnerIndex=355|IndexInSheet=10|OwnerPartId=-1|Location.X=1318|Location.Y=754|Color=8388608|FontID=2|IsHidden=T|Text=100PPM|Name=OTHER
|RECORD=41|OwnerIndex=355|IndexInSheet=11|OwnerPartId=-1|Location.X=1318|Location.Y=754|Color=8388608|FontID=2|IsHidden=T|Text=0603|Name=SIZE
|RECORD=41|OwnerIndex=355|IndexInSheet=12|OwnerPartId=-1|Location.X=1318|Location.Y=754|Color=8388608|FontID=2|IsHidden=T|Text=GENERIC|Name=SUB
|RECORD=41|OwnerIndex=355|IndexInSheet=13|OwnerPartId=-1|Location.X=1318|Location.Y=754|Color=8388608|FontID=2|IsHidden=T|Text=Digi-Key|Name=Supplier 1|ReadOnlyState=3
|RECORD=41|OwnerIndex=355|IndexInSheet=14|OwnerPartId=-1|Location.X=1318|Location.Y=754|Color=8388608|FontID=2|IsHidden=T|Text=P10.0KHCT-ND|Name=Supplier Part Number 1|ReadOnlyState=3
|RECORD=41|OwnerIndex=355|IndexInSheet=15|OwnerPartId=-1|Location.X=1318|Location.Y=754|Color=8388608|FontID=1|IsHidden=T|Text=*|Name=SHEETPART
|RECORD=41|OwnerIndex=355|IndexInSheet=16|OwnerPartId=-1|Location.X=1318|Location.Y=754|Color=8388608|FontID=1|IsHidden=T|Text=RES, 10K, 1%, 1/10W, TF, 0603|Name=DESC
|RECORD=41|OwnerIndex=355|IndexInSheet=17|OwnerPartId=-1|Location.X=1329|Location.Y=734|Color=8388608|FontID=2|Text=10K|Name=VALUE
|RECORD=2|OwnerIndex=355|OwnerPartId=1|FormalType=1|Electrical=4|PinConglomerate=32|PinLength=10|Location.X=1360|Location.Y=750|Name=1|Designator=1|PinPropagationDelay=0.000000E+000
|RECORD=2|OwnerIndex=355|OwnerPartId=1|FormalType=1|Electrical=4|PinConglomerate=34|PinLength=10|Location.X=1330|Location.Y=750|Name=2|Designator=2|PinPropagationDelay=0.000000E+000
|RECORD=6|OwnerIndex=355|IsNotAccesible=T|IndexInSheet=20|OwnerPartId=1|LineWidth=1|Color=16711680|LocationCount=7|X1=1330|Y1=750|X2=1333|Y2=747|X3=1339|Y3=753|X4=1345|Y4=747|X5=1351|Y5=753|X6=1357|Y6=747|X7=1360|Y7=750
|RECORD=41|OwnerIndex=355|IndexInSheet=21|OwnerPartId=-1|Location.X=1318|Location.Y=754|Color=8388608|FontID=1|IsHidden=T|Text=<VELENTIUM>|Name=VELENTIUM PART NUM
|RECORD=34|OwnerIndex=355|IndexInSheet=-1|OwnerPartId=-1|Location.X=1329|Location.Y=754|Color=8388608|FontID=3|Text=R43|Name=Designator|ReadOnlyState=1
|RECORD=41|OwnerIndex=355|IndexInSheet=-1|OwnerPartId=-1|Location.X=1318|Location.Y=754|Color=8388608|FontID=2|IsHidden=T|Text==MFG PART NUM|Name=Comment
|RECORD=44|OwnerIndex=355
|RECORD=45|OwnerIndex=382|IndexInSheet=-1|Description=Chip Resistor, 0603, 2-Leads, Body 1.57x0.85mm, IPC Medium Density|UseComponentLibrary=T|ModelName=RESC1608X50N|ModelType=PCBLIB|DatafileCount=1|ModelDatafileEntity0=RESC1608X50N|ModelDatafileKind0=PCBLib|IsCurrent=T|DatalinksLocked=T|DatabaseDatalinksLocked=T|IntegratedModel=T|DatabaseModel=T
|RECORD=46|OwnerIndex=383
|RECORD=48|OwnerIndex=383
|RECORD=1|LibReference=FT230XS-R|ComponentDescription=IC, TCVR, FT230, USB TO UART, 5V, FTDI, 16SSOP|PartCount=2|DisplayModeCount=1|IndexInSheet=63|OwnerPartId=-1|Location.X=1310|Location.Y=670|IsMirrored=T|CurrentPartId=1|LibraryPath=*|SourceLibraryName=IntegratedCircuits.IntLib|TargetFileName=*|AreaColor=11599871|Color=128|PartIDLocked=F|AliasList=AD7866ARUZ|DesignItemId=FT230XS-R|AllPinCount=16
|RECORD=41|OwnerIndex=386|OwnerPartId=-1|Location.X=1158|Location.Y=862|Color=8388608|FontID=2|IsHidden=T|Text=FT230XS-R|Name=MFG PART NUM|IsMirrored=T
|RECORD=41|OwnerIndex=386|IndexInSheet=1|OwnerPartId=-1|Location.X=1158|Location.Y=862|Color=8388608|FontID=2|IsHidden=T|Text=FTDI|Name=MFG NAME|IsMirrored=T
|RECORD=41|OwnerIndex=386|IndexInSheet=2|OwnerPartId=-1|Location.X=1158|Location.Y=862|Color=8388608|FontID=2|IsHidden=T|Text=8/14/2013|Name=MODIFY DATE|IsMirrored=T
|RECORD=41|OwnerIndex=386|IndexInSheet=3|OwnerPartId=-1|Location.X=1158|Location.Y=862|Color=8388608|FontID=2|IsHidden=T|Text=IC, TCVR|Name=CATEGORY|IsMirrored=T
|RECORD=41|OwnerIndex=386|IndexInSheet=4|OwnerPartId=-1|Location.X=1158|Location.Y=862|Color=8388608|FontID=2|IsHidden=T|Name=DATE|IsMirrored=T
|RECORD=41|OwnerIndex=386|IndexInSheet=5|OwnerPartId=-1|Location.X=1158|Location.Y=862|Color=8388608|FontID=2|IsHidden=T|Text=85C|Name=MAXTEMP|IsMirrored=T
|RECORD=41|OwnerIndex=386|IndexInSheet=6|OwnerPartId=-1|Location.X=1158|Location.Y=862|Color=8388608|FontID=2|IsHidden=T|Text=-40C|Name=MINTEMP|IsMirrored=T
|RECORD=41|OwnerIndex=386|IndexInSheet=7|OwnerPartId=-1|Location.X=1158|Location.Y=862|Color=8388608|FontID=2|IsHidden=T|Name=OTHER|IsMirrored=T
|RECORD=41|OwnerIndex=386|IndexInSheet=8|OwnerPartId=-1|Location.X=1158|Location.Y=862|Color=8388608|FontID=2|IsHidden=T|Text=USB TO UART|Name=P1|IsMirrored=T
|RECORD=41|OwnerIndex=386|IndexInSheet=9|OwnerPartId=-1|Location.X=1158|Location.Y=862|Color=8388608|FontID=2|IsHidden=T|Text=5V|Name=P2|IsMirrored=T
|RECORD=41|OwnerIndex=386|IndexInSheet=10|OwnerPartId=-1|Location.X=1158|Location.Y=862|Color=8388608|FontID=2|IsHidden=T|Text=FTDI|Name=P3|IsMirrored=T
|RECORD=41|OwnerIndex=386|IndexInSheet=11|OwnerPartId=-1|Location.X=1158|Location.Y=862|Color=8388608|FontID=2|IsHidden=T|Text=20SSOP|Name=SIZE|IsMirrored=T
|RECORD=41|OwnerIndex=386|IndexInSheet=12|OwnerPartId=-1|Location.X=1158|Location.Y=862|Color=8388608|FontID=2|IsHidden=T|Name=SUB|IsMirrored=T
|RECORD=41|OwnerIndex=386|IndexInSheet=13|OwnerPartId=-1|Location.X=1158|Location.Y=862|Color=8388608|FontID=1|IsHidden=T|Text=*|Name=SHEETPART|IsMirrored=T
|RECORD=41|OwnerIndex=386|IndexInSheet=14|OwnerPartId=-1|Location.X=1158|Location.Y=862|Color=8388608|FontID=1|IsHidden=T|Text=IC, TCVR, FT230, USB TO UART, 5V, FTDI, 16SSOP|Name=DESC|IsMirrored=T
|RECORD=41|OwnerIndex=386|IndexInSheet=15|OwnerPartId=-1|Location.X=1158|Location.Y=862|Color=8388608|FontID=1|IsHidden=T|Text=<V PART NUM>|Name=VELENTIUM PART NUM|IsMirrored=T
|RECORD=41|OwnerIndex=386|IndexInSheet=16|OwnerPartId=-1|Location.X=1158|Location.Y=862|Color=8388608|FontID=1|IsHidden=T|Text=Digi-Key|Name=Supplier 1|ReadOnlyState=3|IsMirrored=T
|RECORD=41|OwnerIndex=386|IndexInSheet=17|OwnerPartId=-1|Location.X=1158|Location.Y=862|Color=8388608|FontID=1|IsHidden=T|Text=768-1135-1-ND|Name=Supplier Part Number 1|ReadOnlyState=3|IsMirrored=T
|RECORD=41|OwnerIndex=386|IndexInSheet=18|OwnerPartId=-1|Location.X=1312|Location.Y=828|Color=8388608|FontID=2|Text=FT230XS|Name=VALUE|IsMirrored=T
|RECORD=2|OwnerIndex=386|OwnerPartId=1|FormalType=1|Electrical=4|PinConglomerate=56|PinLength=20|Location.X=1290|Location.Y=770|Name=USBDP|Designator=8|PinPropagationDelay=0.000000E+000
|RECORD=2|OwnerIndex=386|OwnerPartId=1|SymBol_OuterEdge=4|FormalType=1|Electrical=4|PinConglomerate=58|PinLength=20|Location.X=1180|Location.Y=800|Name=CTS#|Designator=6|PinPropagationDelay=0.000000E+000
|RECORD=2|OwnerIndex=386|OwnerPartId=1|FormalType=1|Electrical=4|PinConglomerate=56|PinLength=20|Location.X=1290|Location.Y=750|Name=RESET#|Designator=11|PinPropagationDelay=0.000000E+000
|RECORD=2|OwnerIndex=386|OwnerPartId=1|FormalType=1|Electrical=4|PinConglomerate=57|PinLength=20|Location.X=1240|Location.Y=840|Name=VCC|Designator=12|PinPropagationDelay=0.000000E+000
|RECORD=2|OwnerIndex=386|OwnerPartId=1|FormalType=1|Electrical=4|PinConglomerate=57|PinLength=20|Location.X=1220|Location.Y=840|Name=VCCIO|Designator=3|PinPropagationDelay=0.000000E+000
|RECORD=2|OwnerIndex=386|OwnerPartId=1|SymBol_OuterEdge=17|FormalType=1|Electrical=4|PinConglomerate=58|PinLength=20|Location.X=1180|Location.Y=830|Name=TXD|Designator=1|PinPropagationDelay=0.000000E+000
|RECORD=2|OwnerIndex=386|OwnerPartId=1|SymBol_OuterEdge=17|FormalType=1|Electrical=4|PinConglomerate=58|PinLength=20|Location.X=1180|Location.Y=810|Name=RTS#|Designator=2|PinPropagationDelay=0.000000E+000
|RECORD=2|OwnerIndex=386|OwnerPartId=1|FormalType=1|Electrical=4|PinConglomerate=56|PinLength=20|Location.X=1290|Location.Y=820|Name=3V3OUT|Designator=10|PinPropagationDelay=0.000000E+000
|RECORD=2|OwnerIndex=386|OwnerPartId=1|FormalType=1|Electrical=4|PinConglomerate=56|PinLength=20|Location.X=1290|Location.Y=790|Name=USBDM|Designator=9|PinPropagationDelay=0.000000E+000
|RECORD=2|OwnerIndex=386|OwnerPartId=1|SymBol_OuterEdge=4|FormalType=1|Electrical=4|PinConglomerate=58|PinLength=20|Location.X=1180|Location.Y=820|Name=RXD|Designator=4|PinPropagationDelay=0.000000E+000
|RECORD=2|OwnerIndex=386|OwnerPartId=1|FormalType=1|Electrical=4|PinConglomerate=58|PinLength=20|Location.X=1180|Location.Y=750|Name=CBUS3|Designator=16|PinPropagationDelay=0.000000E+000
|RECORD=2|OwnerIndex=386|OwnerPartId=1|FormalType=1|Electrical=4|PinConglomerate=58|PinLength=20|Location.X=1180|Location.Y=780|Name=CBUS0|Designator=15|PinPropagationDelay=0.000000E+000
|RECORD=2|OwnerIndex=386|OwnerPartId=1|FormalType=1|Electrical=4|PinConglomerate=58|PinLength=20|Location.X=1180|Location.Y=760|Name=CBUS2|Designator=7|PinPropagationDelay=0.000000E+000
|RECORD=2|OwnerIndex=386|OwnerPartId=1|FormalType=1|Electrical=4|PinConglomerate=58|PinLength=20|Location.X=1180|Location.Y=770|Name=CBUS1|Designator=14|PinPropagationDelay=0.000000E+000
|RECORD=2|OwnerIndex=386|OwnerPartId=1|FormalType=1|Electrical=4|PinConglomerate=59|PinLength=20|Location.X=1220|Location.Y=740|Name=GND|Designator=13|PinPropagationDelay=0.000000E+000
|RECORD=2|OwnerIndex=386|OwnerPartId=1|FormalType=1|Electrical=4|PinConglomerate=59|PinLength=20|Location.X=1240|Location.Y=740|Name=GND|Designator=5|PinPropagationDelay=0.000000E+000
|RECORD=14|OwnerIndex=386|IsNotAccesible=T|IndexInSheet=35|OwnerPartId=1|Location.X=1180|Location.Y=740|Corner.X=1290|Corner.Y=840|Color=128|AreaColor=11599871|IsSolid=T|Transparent=T
|RECORD=34|OwnerIndex=386|IndexInSheet=-1|OwnerPartId=-1|Location.X=1312|Location.Y=840|Color=8388608|FontID=3|Text=U16|Name=Designator|ReadOnlyState=1|IsMirrored=T
|RECORD=41|OwnerIndex=386|IndexInSheet=-1|OwnerPartId=-1|Location.X=1158|Location.Y=862|Color=8388608|FontID=2|IsHidden=T|Text==MFG PART NUM|Name=Comment|ReadOnlyState=1|IsMirrored=T
|RECORD=44|OwnerIndex=386
|RECORD=45|OwnerIndex=441|IndexInSheet=-1|Description=SOP, 16-Leads, Body 4.90x3.90mm, Pitch 0.64mm, IPC Medium Density|UseComponentLibrary=T|ModelName=SOP64P600X170-16N|ModelType=PCBLIB|DatafileCount=1|ModelDatafileEntity0=SOP64P600X170-16N|ModelDatafileKind0=PCBLib|IsCurrent=T|DatalinksLocked=T|DatabaseDatalinksLocked=T|IntegratedModel=T|DatabaseModel=T
|RECORD=46|OwnerIndex=442
|RECORD=48|OwnerIndex=442
|RECORD=22|IndexInSheet=64|OwnerPartId=-1|Location.X=1450|Location.Y=800|Color=255|Orientation=1|Symbol=Thin Cross|IsActive=T|SuppressAll=T
|RECORD=17|IndexInSheet=65|OwnerPartId=-1|ShowNetName=T|Location.X=1430|Location.Y=940|Orientation=1|Color=128|FontID=1|Text=+5.0V
|RECORD=17|IndexInSheet=66|OwnerPartId=-1|Style=4|ShowNetName=T|Location.X=1240|Location.Y=700|Orientation=3|Color=128|FontID=1|Text=GND
|RECORD=22|IndexInSheet=67|OwnerPartId=-1|Location.X=1160|Location.Y=810|Color=255|Orientation=1|Symbol=Thin Cross|IsActive=T|SuppressAll=T
|RECORD=22|IndexInSheet=68|OwnerPartId=-1|Location.X=1160|Location.Y=800|Color=255|Orientation=1|Symbol=Thin Cross|IsActive=T|SuppressAll=T
|RECORD=22|IndexInSheet=69|OwnerPartId=-1|Location.X=1160|Location.Y=780|Color=255|Orientation=1|Symbol=Thin Cross|IsActive=T|SuppressAll=T
|RECORD=22|IndexInSheet=70|OwnerPartId=-1|Location.X=1160|Location.Y=760|Color=255|Orientation=1|Symbol=Thin Cross|IsActive=T|SuppressAll=T
|RECORD=22|IndexInSheet=71|OwnerPartId=-1|Location.X=1160|Location.Y=750|Color=255|Orientation=1|Symbol=Thin Cross|IsActive=T|SuppressAll=T
|RECORD=22|IndexInSheet=72|OwnerPartId=-1|Location.X=1160|Location.Y=770|Color=255|Orientation=1|Symbol=Thin Cross|IsActive=T|SuppressAll=T
|RECORD=17|IndexInSheet=73|OwnerPartId=-1|ShowNetName=T|Location.X=890|Location.Y=850|Orientation=2|Color=255|FontID=1|Text=GPS1_TX|IsCrossSheetConnector=T
|RECORD=17|IndexInSheet=74|OwnerPartId=-1|ShowNetName=T|Location.X=890|Location.Y=780|Orientation=2|Color=255|FontID=1|Text=GPS1_RX|IsCrossSheetConnector=T
|RECORD=1|LibReference=JUMPER_3PIN|ComponentDescription=CONN, HDR, 1X3, VERT, .1, JUMPER, TH|PartCount=2|DisplayModeCount=1|IndexInSheet=75|OwnerPartId=-1|Location.X=970|Location.Y=880|Orientation=1|CurrentPartId=1|LibraryPath=*|SourceLibraryName=Connectors.IntLib|TargetFileName=*|AreaColor=11599871|Color=128|PartIDLocked=F|DesignItemId=JUMPER_3PIN|AllPinCount=3
|RECORD=41|OwnerIndex=456|OwnerPartId=-1|Location.X=970|Location.Y=900|Color=8388608|FontID=2|IsHidden=T|Text=CONN, HDR|Name=CATEGORY
|RECORD=41|OwnerIndex=456|IndexInSheet=1|OwnerPartId=-1|Location.X=970|Location.Y=900|Color=8388608|FontID=2|IsHidden=T|Text=SAMTEC|Name=MFG NAME
|RECORD=41|OwnerIndex=456|IndexInSheet=2|OwnerPartId=-1|Location.X=970|Location.Y=900|Color=8388608|FontID=2|IsHidden=T|Text=10/10/2013|Name=MODIFY DATE
|RECORD=41|OwnerIndex=456|IndexInSheet=3|OwnerPartId=-1|Location.X=970|Location.Y=900|Color=8388608|FontID=2|IsHidden=T|Text=TSW-103-08-G-S|Name=MFG PART NUM
|RECORD=41|OwnerIndex=456|IndexInSheet=4|OwnerPartId=-1|Location.X=970|Location.Y=900|Color=8388608|FontID=2|IsHidden=T|Text=C|Name=MAXTEMP
|RECORD=41|OwnerIndex=456|IndexInSheet=5|OwnerPartId=-1|Location.X=970|Location.Y=900|Color=8388608|FontID=2|IsHidden=T|Text=C|Name=MINTEMP
|RECORD=41|OwnerIndex=456|IndexInSheet=6|OwnerPartId=-1|Location.X=970|Location.Y=900|Color=8388608|FontID=2|IsHidden=T|Text=TSW-1XX|Name=OTHER
|RECORD=41|OwnerIndex=456|IndexInSheet=7|OwnerPartId=-1|Location.X=970|Location.Y=900|Color=8388608|FontID=2|IsHidden=T|Text=VERT|Name=P1
|RECORD=41|OwnerIndex=456|IndexInSheet=8|OwnerPartId=-1|Location.X=970|Location.Y=900|Color=8388608|FontID=2|IsHidden=T|Text=.1|Name=P2
|RECORD=41|OwnerIndex=456|IndexInSheet=9|OwnerPartId=-1|Location.X=970|Location.Y=900|Color=8388608|FontID=2|IsHidden=T|Text=FEATURE|Name=P3
|RECORD=41|OwnerIndex=456|IndexInSheet=10|OwnerPartId=-1|Location.X=970|Location.Y=900|Color=8388608|FontID=2|IsHidden=T|Text=TH|Name=SIZE
|RECORD=41|OwnerIndex=456|IndexInSheet=11|OwnerPartId=-1|Location.X=970|Location.Y=900|Color=8388608|FontID=2|IsHidden=T|Name=SUB
|RECORD=41|OwnerIndex=456|IndexInSheet=12|OwnerPartId=-1|Location.X=970|Location.Y=900|Color=8388608|FontID=2|IsHidden=T|Name=SHEETPART
|RECORD=41|OwnerIndex=456|IndexInSheet=13|OwnerPartId=-1|Location.X=970|Location.Y=900|Color=8388608|FontID=2|IsHidden=T|Name=DATE
|RECORD=41|OwnerIndex=456|IndexInSheet=14|OwnerPartId=-1|Location.X=970|Location.Y=900|Color=8388608|FontID=2|IsHidden=T|Text=Digi-Key|Name=Supplier 1|ReadOnlyState=3
|RECORD=41|OwnerIndex=456|IndexInSheet=15|OwnerPartId=-1|Location.X=970|Location.Y=900|Color=8388608|FontID=2|IsHidden=T|Text=SAM1038-02-ND|Name=Supplier Part Number 1|ReadOnlyState=3
|RECORD=41|OwnerIndex=456|IndexInSheet=16|OwnerPartId=-1|Location.X=970|Location.Y=900|Color=8388608|FontID=1|IsHidden=T|Text=CONN, HDR, 1X3, VERT, .1, JUMPER, TH|Name=DESC
|RECORD=41|OwnerIndex=456|IndexInSheet=17|OwnerPartId=-1|Location.X=970|Location.Y=900|Color=8388608|FontID=1|IsHidden=T|Text=<VALENTIUM>|Name=VALENTIUM PART NUM
|RECORD=41|OwnerIndex=456|IndexInSheet=18|OwnerPartId=-1|Location.X=1010|Location.Y=890|Color=8388608|FontID=2|Text=1X3|Name=VALUE
|RECORD=14|OwnerIndex=456|IsNotAccesible=T|IndexInSheet=19|OwnerPartId=1|Location.X=970|Location.Y=880|Corner.X=1010|Corner.Y=900|Color=128|AreaColor=11599871|IsSolid=T
|RECORD=2|OwnerIndex=456|OwnerPartId=1|FormalType=1|Electrical=4|PinConglomerate=59|PinLength=30|Location.X=980|Location.Y=880|Name=1|Designator=1|SwapIDPart=Ž&Ž||PinPropagationDelay=0.000000E+000
|RECORD=2|OwnerIndex=456|OwnerPartId=1|FormalType=1|Electrical=4|PinConglomerate=59|PinLength=30|Location.X=990|Location.Y=880|Name=2|Designator=2|SwapIDPart=Ž&Ž||PinPropagationDelay=0.000000E+000
|RECORD=2|OwnerIndex=456|OwnerPartId=1|FormalType=1|Electrical=4|PinConglomerate=59|PinLength=30|Location.X=1000|Location.Y=880|Name=3|Designator=3|SwapIDPart=Ž&Ž||PinPropagationDelay=0.000000E+000
|RECORD=34|OwnerIndex=456|IndexInSheet=-1|OwnerPartId=-1|Location.X=970|Location.Y=900|Color=8388608|FontID=3|Text=JP1|Name=Designator|ReadOnlyState=1
|RECORD=41|OwnerIndex=456|IndexInSheet=-1|OwnerPartId=-1|Location.X=970|Location.Y=900|Color=8388608|FontID=2|IsHidden=T|Text=JUMPER_3PIN|Name=Comment
|RECORD=44|OwnerIndex=456
|RECORD=45|OwnerIndex=485|IndexInSheet=-1|Description=3Pin solder for flex cable|UseComponentLibrary=T|ModelName=3PINV-100|ModelType=PCBLIB|DatafileCount=1|ModelDatafileEntity0=3PINV-100|ModelDatafileKind0=PCBLib|IsCurrent=T|DatalinksLocked=T|DatabaseDatalinksLocked=T|IntegratedModel=T|DatabaseModel=T
|RECORD=46|OwnerIndex=486
|RECORD=48|OwnerIndex=486
|RECORD=1|LibReference=JUMPER_3PIN|ComponentDescription=CONN, HDR, 1X3, VERT, .1, JUMPER, TH|PartCount=2|DisplayModeCount=1|IndexInSheet=76|OwnerPartId=-1|Location.X=1040|Location.Y=880|Orientation=1|CurrentPartId=1|LibraryPath=*|SourceLibraryName=Connectors.IntLib|TargetFileName=*|AreaColor=11599871|Color=128|PartIDLocked=F|DesignItemId=JUMPER_3PIN|AllPinCount=3
|RECORD=41|OwnerIndex=489|OwnerPartId=-1|Location.X=1040|Location.Y=900|Color=8388608|FontID=2|IsHidden=T|Text=CONN, HDR|Name=CATEGORY
|RECORD=41|OwnerIndex=489|IndexInSheet=1|OwnerPartId=-1|Location.X=1040|Location.Y=900|Color=8388608|FontID=2|IsHidden=T|Text=SAMTEC|Name=MFG NAME
|RECORD=41|OwnerIndex=489|IndexInSheet=2|OwnerPartId=-1|Location.X=1040|Location.Y=900|Color=8388608|FontID=2|IsHidden=T|Text=10/10/2013|Name=MODIFY DATE
|RECORD=41|OwnerIndex=489|IndexInSheet=3|OwnerPartId=-1|Location.X=1040|Location.Y=900|Color=8388608|FontID=2|IsHidden=T|Text=TSW-103-08-G-S|Name=MFG PART NUM
|RECORD=41|OwnerIndex=489|IndexInSheet=4|OwnerPartId=-1|Location.X=1040|Location.Y=900|Color=8388608|FontID=2|IsHidden=T|Text=C|Name=MAXTEMP
|RECORD=41|OwnerIndex=489|IndexInSheet=5|OwnerPartId=-1|Location.X=1040|Location.Y=900|Color=8388608|FontID=2|IsHidden=T|Text=C|Name=MINTEMP
|RECORD=41|OwnerIndex=489|IndexInSheet=6|OwnerPartId=-1|Location.X=1040|Location.Y=900|Color=8388608|FontID=2|IsHidden=T|Text=TSW-1XX|Name=OTHER
|RECORD=41|OwnerIndex=489|IndexInSheet=7|OwnerPartId=-1|Location.X=1040|Location.Y=900|Color=8388608|FontID=2|IsHidden=T|Text=VERT|Name=P1
|RECORD=41|OwnerIndex=489|IndexInSheet=8|OwnerPartId=-1|Location.X=1040|Location.Y=900|Color=8388608|FontID=2|IsHidden=T|Text=.1|Name=P2
|RECORD=41|OwnerIndex=489|IndexInSheet=9|OwnerPartId=-1|Location.X=1040|Location.Y=900|Color=8388608|FontID=2|IsHidden=T|Text=FEATURE|Name=P3
|RECORD=41|OwnerIndex=489|IndexInSheet=10|OwnerPartId=-1|Location.X=1040|Location.Y=900|Color=8388608|FontID=2|IsHidden=T|Text=TH|Name=SIZE
|RECORD=41|OwnerIndex=489|IndexInSheet=11|OwnerPartId=-1|Location.X=1040|Location.Y=900|Color=8388608|FontID=2|IsHidden=T|Name=SUB
|RECORD=41|OwnerIndex=489|IndexInSheet=12|OwnerPartId=-1|Location.X=1040|Location.Y=900|Color=8388608|FontID=2|IsHidden=T|Name=SHEETPART
|RECORD=41|OwnerIndex=489|IndexInSheet=13|OwnerPartId=-1|Location.X=1040|Location.Y=900|Color=8388608|FontID=2|IsHidden=T|Name=DATE
|RECORD=41|OwnerIndex=489|IndexInSheet=14|OwnerPartId=-1|Location.X=1040|Location.Y=900|Color=8388608|FontID=2|IsHidden=T|Text=Digi-Key|Name=Supplier 1|ReadOnlyState=3
|RECORD=41|OwnerIndex=489|IndexInSheet=15|OwnerPartId=-1|Location.X=1040|Location.Y=900|Color=8388608|FontID=2|IsHidden=T|Text=SAM1038-02-ND|Name=Supplier Part Number 1|ReadOnlyState=3
|RECORD=41|OwnerIndex=489|IndexInSheet=16|OwnerPartId=-1|Location.X=1040|Location.Y=900|Color=8388608|FontID=1|IsHidden=T|Text=CONN, HDR, 1X3, VERT, .1, JUMPER, TH|Name=DESC
|RECORD=41|OwnerIndex=489|IndexInSheet=17|OwnerPartId=-1|Location.X=1040|Location.Y=900|Color=8388608|FontID=1|IsHidden=T|Text=<VALENTIUM>|Name=VALENTIUM PART NUM
|RECORD=41|OwnerIndex=489|IndexInSheet=18|OwnerPartId=-1|Location.X=1080|Location.Y=890|Color=8388608|FontID=2|Text=1X3|Name=VALUE
|RECORD=14|OwnerIndex=489|IsNotAccesible=T|IndexInSheet=19|OwnerPartId=1|Location.X=1040|Location.Y=880|Corner.X=1080|Corner.Y=900|Color=128|AreaColor=11599871|IsSolid=T
|RECORD=2|OwnerIndex=489|OwnerPartId=1|FormalType=1|Electrical=4|PinConglomerate=59|PinLength=30|Location.X=1050|Location.Y=880|Name=1|Designator=1|SwapIDPart=Ž&Ž||PinPropagationDelay=0.000000E+000
|RECORD=2|OwnerIndex=489|OwnerPartId=1|FormalType=1|Electrical=4|PinConglomerate=59|PinLength=30|Location.X=1060|Location.Y=880|Name=2|Designator=2|SwapIDPart=Ž&Ž||PinPropagationDelay=0.000000E+000
|RECORD=2|OwnerIndex=489|OwnerPartId=1|FormalType=1|Electrical=4|PinConglomerate=59|PinLength=30|Location.X=1070|Location.Y=880|Name=3|Designator=3|SwapIDPart=Ž&Ž||PinPropagationDelay=0.000000E+000
|RECORD=34|OwnerIndex=489|IndexInSheet=-1|OwnerPartId=-1|Location.X=1040|Location.Y=900|Color=8388608|FontID=3|Text=JP2|Name=Designator|ReadOnlyState=1
|RECORD=41|OwnerIndex=489|IndexInSheet=-1|OwnerPartId=-1|Location.X=1040|Location.Y=900|Color=8388608|FontID=2|IsHidden=T|Text=JUMPER_3PIN|Name=Comment
|RECORD=44|OwnerIndex=489
|RECORD=45|OwnerIndex=518|IndexInSheet=-1|Description=3Pin solder for flex cable|UseComponentLibrary=T|ModelName=3PINV-100|ModelType=PCBLIB|DatafileCount=1|ModelDatafileEntity0=3PINV-100|ModelDatafileKind0=PCBLib|IsCurrent=T|DatalinksLocked=T|DatabaseDatalinksLocked=T|IntegratedModel=T|DatabaseModel=T
|RECORD=46|OwnerIndex=519
|RECORD=48|OwnerIndex=519
|RECORD=1|LibReference=USB_B_473461001|ComponentDescription=CONN, REC, USB, R/A, MICRO, TYPE B, 5 POS, SMT FLANGELESS|PartCount=2|DisplayModeCount=1|IndexInSheet=77|OwnerPartId=-1|Location.X=1510|Location.Y=730|IsMirrored=T|CurrentPartId=1|LibraryPath=*|SourceLibraryName=Connectors.IntLib|TargetFileName=*|AreaColor=11599871|Color=128|PartIDLocked=F|DesignItemId=USB_B_473461001|AllPinCount=5
|RECORD=41|OwnerIndex=522|OwnerPartId=-1|Location.X=1448|Location.Y=810|Color=8388608|FontID=2|IsHidden=T|Text=CONN, REC|Name=CATEGORY|IsMirrored=T
|RECORD=41|OwnerIndex=522|IndexInSheet=1|OwnerPartId=-1|Location.X=1448|Location.Y=810|Color=8388608|FontID=2|IsHidden=T|Text=MOLEX|Name=MFG NAME|IsMirrored=T
|RECORD=41|OwnerIndex=522|IndexInSheet=2|OwnerPartId=-1|Location.X=1448|Location.Y=810|Color=8388608|FontID=2|IsHidden=T|Text=10/10/2013|Name=MODIFY DATE|IsMirrored=T
|RECORD=41|OwnerIndex=522|IndexInSheet=3|OwnerPartId=-1|Location.X=1448|Location.Y=810|Color=8388608|FontID=2|IsHidden=T|Text=85C|Name=MAXTEMP|IsMirrored=T
|RECORD=41|OwnerIndex=522|IndexInSheet=4|OwnerPartId=-1|Location.X=1448|Location.Y=810|Color=8388608|FontID=2|IsHidden=T|Text=-30C|Name=MINTEMP|IsMirrored=T
|RECORD=41|OwnerIndex=522|IndexInSheet=5|OwnerPartId=-1|Location.X=1448|Location.Y=810|Color=8388608|FontID=2|IsHidden=T|Text=FLANGELESS|Name=OTHER|IsMirrored=T
|RECORD=41|OwnerIndex=522|IndexInSheet=6|OwnerPartId=-1|Location.X=1448|Location.Y=810|Color=8388608|FontID=2|IsHidden=T|Text=R/A|Name=P1|IsMirrored=T
|RECORD=41|OwnerIndex=522|IndexInSheet=7|OwnerPartId=-1|Location.X=1448|Location.Y=810|Color=8388608|FontID=2|IsHidden=T|Text=5 POS|Name=P2|IsMirrored=T
|RECORD=41|OwnerIndex=522|IndexInSheet=8|OwnerPartId=-1|Location.X=1448|Location.Y=810|Color=8388608|FontID=2|IsHidden=T|Text=USB MICRO B|Name=P3|IsMirrored=T
|RECORD=41|OwnerIndex=522|IndexInSheet=9|OwnerPartId=-1|Location.X=1448|Location.Y=810|Color=8388608|FontID=2|IsHidden=T|Text=SMT|Name=SIZE|IsMirrored=T
|RECORD=41|OwnerIndex=522|IndexInSheet=10|OwnerPartId=-1|Location.X=1448|Location.Y=810|Color=8388608|FontID=2|IsHidden=T|Name=SUB|IsMirrored=T
|RECORD=41|OwnerIndex=522|IndexInSheet=11|OwnerPartId=-1|Location.X=1448|Location.Y=810|Color=8388608|FontID=2|IsHidden=T|Text=473461001|Name=MFG PART NUM|IsMirrored=T
|RECORD=41|OwnerIndex=522|IndexInSheet=12|OwnerPartId=-1|Location.X=1448|Location.Y=810|Color=8388608|FontID=2|IsHidden=T|Name=SHEETPART|IsMirrored=T
|RECORD=41|OwnerIndex=522|IndexInSheet=13|OwnerPartId=-1|Location.X=1448|Location.Y=810|Color=8388608|FontID=2|IsHidden=T|Name=DATE|IsMirrored=T
|RECORD=41|OwnerIndex=522|IndexInSheet=14|OwnerPartId=-1|Location.X=1448|Location.Y=810|Color=8388608|FontID=1|IsHidden=T|Text=CONN, REC, USB, R/A, MICRO, TYPE B, 5 POS, SMT FLANGELESS|Name=DESC|IsMirrored=T
|RECORD=41|OwnerIndex=522|IndexInSheet=15|OwnerPartId=-1|Location.X=1448|Location.Y=810|Color=8388608|FontID=1|IsHidden=T|Text=Digi-Key|Name=Supplier 1|ReadOnlyState=3|IsMirrored=T
|RECORD=41|OwnerIndex=522|IndexInSheet=16|OwnerPartId=-1|Location.X=1448|Location.Y=810|Color=8388608|FontID=1|IsHidden=T|Text=WM11228CT-ND|Name=Supplier Part Number 1|ReadOnlyState=3|IsMirrored=T
|RECORD=41|OwnerIndex=522|IndexInSheet=17|OwnerPartId=-1|Location.X=1470|Location.Y=738|Color=8388608|FontID=2|Text=USB MICRO B|Name=VALUE|IsMirrored=T
|RECORD=14|OwnerIndex=522|IsNotAccesible=T|IndexInSheet=18|OwnerPartId=1|Location.X=1470|Location.Y=750|Corner.X=1540|Corner.Y=810|Color=128|AreaColor=11599871|IsSolid=T
|RECORD=2|OwnerIndex=522|OwnerPartId=1|FormalType=1|Electrical=4|PinConglomerate=58|PinLength=20|Location.X=1470|Location.Y=800|Name=V_BUS (RED)|Designator=1|PinPropagationDelay=0.000000E+000
|RECORD=2|OwnerIndex=522|OwnerPartId=1|FormalType=1|Electrical=4|PinConglomerate=58|PinLength=20|Location.X=1470|Location.Y=790|Name=DM (WHT)|Designator=2|PinPropagationDelay=0.000000E+000
|RECORD=2|OwnerIndex=522|OwnerPartId=1|FormalType=1|Electrical=4|PinConglomerate=58|PinLength=20|Location.X=1470|Location.Y=780|Name=DP (GRN)|Designator=3|PinPropagationDelay=0.000000E+000
|RECORD=2|OwnerIndex=522|OwnerPartId=1|FormalType=1|Electrical=4|PinConglomerate=58|PinLength=20|Location.X=1470|Location.Y=770|Name=ID|Designator=4|PinPropagationDelay=0.000000E+000
|RECORD=2|OwnerIndex=522|OwnerPartId=1|FormalType=1|Electrical=4|PinConglomerate=58|PinLength=20|Location.X=1470|Location.Y=760|Name=GND (BLK)|Designator=5|PinPropagationDelay=0.000000E+000
|RECORD=41|OwnerIndex=522|IndexInSheet=24|OwnerPartId=-1|Location.X=1448|Location.Y=810|Color=8388608|FontID=1|IsHidden=T|Text=<VALENTIUM>|Name=VALENTIUM PART NUM|IsMirrored=T
|RECORD=34|OwnerIndex=522|IndexInSheet=-1|OwnerPartId=-1|Location.X=1470|Location.Y=810|Color=8388608|FontID=3|Text=J4|Name=Designator|ReadOnlyState=1|IsMirrored=T
|RECORD=41|OwnerIndex=522|IndexInSheet=-1|OwnerPartId=-1|Location.X=1448|Location.Y=810|Color=8388608|FontID=2|IsHidden=T|Text=473461001|Name=Comment|IsMirrored=T
|RECORD=44|OwnerIndex=522
|RECORD=45|OwnerIndex=555|IndexInSheet=-1|Description=USB-MICRO B FLANGELESS BOTTOM MNT|UseComponentLibrary=T|ModelName=USB_47346-1001|ModelType=PCBLIB|DatafileCount=1|ModelDatafileEntity0=USB_47346-1001|ModelDatafileKind0=PCBLib|IsCurrent=T|DatalinksLocked=T|DatabaseDatalinksLocked=T|IntegratedModel=T|DatabaseModel=T
|RECORD=46|OwnerIndex=556
|RECORD=48|OwnerIndex=556
|RECORD=17|IndexInSheet=78|OwnerPartId=-1|ShowNetName=T|Location.X=890|Location.Y=760|Orientation=2|Color=255|FontID=1|Text=GPS2_RX|IsCrossSheetConnector=T
|RECORD=17|IndexInSheet=79|OwnerPartId=-1|ShowNetName=T|Location.X=890|Location.Y=830|Orientation=2|Color=255|FontID=1|Text=GPS2_TX|IsCrossSheetConnector=T
|RECORD=22|IndexInSheet=80|OwnerPartId=-1|Location.X=410|Location.Y=360|Color=255|Orientation=1|Symbol=Thin Cross|IsActive=T|SuppressAll=T
|RECORD=22|IndexInSheet=81|OwnerPartId=-1|Location.X=410|Location.Y=300|Color=255|Orientation=1|Symbol=Thin Cross|IsActive=T|SuppressAll=T
|RECORD=22|IndexInSheet=82|OwnerPartId=-1|Location.X=410|Location.Y=290|Color=255|Orientation=1|Symbol=Thin Cross|IsActive=T|SuppressAll=T
|RECORD=22|IndexInSheet=83|OwnerPartId=-1|Location.X=410|Location.Y=250|Color=255|Orientation=1|Symbol=Thin Cross|IsActive=T|SuppressAll=T
|RECORD=22|IndexInSheet=84|OwnerPartId=-1|Location.X=410|Location.Y=240|Color=255|Orientation=1|Symbol=Thin Cross|IsActive=T|SuppressAll=T
|RECORD=22|IndexInSheet=85|OwnerPartId=-1|Location.X=600|Location.Y=320|Color=255|Orientation=1|Symbol=Thin Cross|IsActive=T|SuppressAll=T
|RECORD=22|IndexInSheet=86|OwnerPartId=-1|Location.X=600|Location.Y=310|Color=255|Orientation=1|Symbol=Thin Cross|IsActive=T|SuppressAll=T
|RECORD=22|IndexInSheet=87|OwnerPartId=-1|Location.X=600|Location.Y=300|Color=255|Orientation=1|Symbol=Thin Cross|IsActive=T|SuppressAll=T
|RECORD=22|IndexInSheet=88|OwnerPartId=-1|Location.X=600|Location.Y=290|Color=255|Orientation=1|Symbol=Thin Cross|IsActive=T|SuppressAll=T
|RECORD=17|IndexInSheet=89|OwnerPartId=-1|Style=4|ShowNetName=T|Location.X=390|Location.Y=210|Orientation=3|Color=128|FontID=1|Text=GND
|RECORD=17|IndexInSheet=90|OwnerPartId=-1|Style=4|ShowNetName=T|Location.X=620|Location.Y=210|Orientation=3|Color=128|FontID=1|Text=GND
|RECORD=17|IndexInSheet=91|OwnerPartId=-1|ShowNetName=T|Location.X=200|Location.Y=370|Orientation=1|Color=128|FontID=1|Text=+3.3V
|RECORD=17|IndexInSheet=92|OwnerPartId=-1|Style=4|ShowNetName=T|Location.X=200|Location.Y=290|Orientation=3|Color=128|FontID=1|Text=GND
|RECORD=17|IndexInSheet=93|OwnerPartId=-1|ShowNetName=T|Location.X=620|Location.Y=370|Orientation=1|Color=128|FontID=1|Text=+3.3V
|RECORD=17|IndexInSheet=94|OwnerPartId=-1|ShowNetName=T|Location.X=660|Location.Y=230|Color=255|FontID=1|Text=IMU_ENV_SCL|IsCrossSheetConnector=T
|RECORD=17|IndexInSheet=95|OwnerPartId=-1|ShowNetName=T|Location.X=660|Location.Y=240|Color=255|FontID=1|Text=IMU_ENV_SDA|IsCrossSheetConnector=T
|RECORD=17|IndexInSheet=96|OwnerPartId=-1|ShowNetName=T|Location.X=660|Location.Y=250|Color=255|FontID=1|Text=MOSI|IsCrossSheetConnector=T
|RECORD=17|IndexInSheet=97|OwnerPartId=-1|ShowNetName=T|Location.X=660|Location.Y=260|Color=255|FontID=1|Text=CSN|IsCrossSheetConnector=T
|RECORD=17|IndexInSheet=98|OwnerPartId=-1|ShowNetName=T|Location.X=660|Location.Y=270|Color=255|FontID=1|Text=SCK|IsCrossSheetConnector=T
|RECORD=17|IndexInSheet=99|OwnerPartId=-1|ShowNetName=T|Location.X=660|Location.Y=280|Color=255|FontID=1|Text=MISO|IsCrossSheetConnector=T
|RECORD=17|IndexInSheet=100|OwnerPartId=-1|ShowNetName=T|Location.X=360|Location.Y=330|Orientation=2|Color=255|FontID=1|Text=IMU_BOOT|IsCrossSheetConnector=T
|RECORD=17|IndexInSheet=101|OwnerPartId=-1|ShowNetName=T|Location.X=360|Location.Y=320|Orientation=2|Color=255|FontID=1|Text=IMU_PS1|IsCrossSheetConnector=T
|RECORD=17|IndexInSheet=102|OwnerPartId=-1|ShowNetName=T|Location.X=360|Location.Y=310|Orientation=2|Color=255|FontID=1|Text=IMU_PS0|IsCrossSheetConnector=T
|RECORD=17|IndexInSheet=103|OwnerPartId=-1|ShowNetName=T|Location.X=360|Location.Y=270|Orientation=2|Color=255|FontID=1|Text=IMU_CLKSEL0|IsCrossSheetConnector=T
|RECORD=17|IndexInSheet=104|OwnerPartId=-1|ShowNetName=T|Location.X=360|Location.Y=260|Orientation=2|Color=255|FontID=1|Text=IMU_NRST|IsCrossSheetConnector=T
|RECORD=17|IndexInSheet=105|OwnerPartId=-1|ShowNetName=T|Location.X=360|Location.Y=230|Orientation=2|Color=255|FontID=1|Text=IMU_INT|IsCrossSheetConnector=T
|RECORD=4|IndexInSheet=106|OwnerPartId=-1|Location.X=480|Location.Y=410|Color=8388608|FontID=4|Text=IMU
|RECORD=1|LibReference=CAP_0805_10UF_25V|ComponentDescription=CAP, CER, 10.UF, 25V, 10%, X5R, 0805|PartCount=2|DisplayModeCount=1|IndexInSheet=107|OwnerPartId=-1|Location.X=180|Location.Y=280|CurrentPartId=1|LibraryPath=*|SourceLibraryName=Capacitors.IntLib|TargetFileName=*|AreaColor=11599871|Color=128|PartIDLocked=F|DesignItemId=CAP_0805_10UF_25V|AllPinCount=2
|RECORD=41|OwnerIndex=588|OwnerPartId=-1|Location.X=180|Location.Y=280|Color=8388608|FontID=2|IsHidden=T|Text=TAIYO YUDEN|Name=MFG NAME
|RECORD=41|OwnerIndex=588|IndexInSheet=1|OwnerPartId=-1|Location.X=180|Location.Y=280|Color=8388608|FontID=2|IsHidden=T|Text=TMK212BBJ106KG-T|Name=MFG PART NUM
|RECORD=41|OwnerIndex=588|IndexInSheet=2|OwnerPartId=-1|Location.X=180|Location.Y=280|Color=8388608|FontID=2|IsHidden=T|Text=10/23/2013|Name=MODIFY DATE
|RECORD=41|OwnerIndex=588|IndexInSheet=3|OwnerPartId=-1|Location.X=180|Location.Y=280|Color=8388608|FontID=2|IsHidden=T|Text=CAP, CER|Name=CATEGORY
|RECORD=41|OwnerIndex=588|IndexInSheet=4|OwnerPartId=-1|Location.X=178|Location.Y=292|Location.Y_Frac=50000|Color=8388608|FontID=2|IsHidden=T|Text=4/11/2006 3:37:28 PM|Name=Date
|RECORD=41|OwnerIndex=588|IndexInSheet=5|OwnerPartId=-1|Location.X=186|Location.Y=354|Location.Y_Frac=48252|Color=8388608|FontID=2|IsHidden=T|Text=*|Name=SHEETPART
|RECORD=41|OwnerIndex=588|IndexInSheet=6|OwnerPartId=-1|Location.X=186|Location.Y=354|Location.Y_Frac=48252|Color=8388608|FontID=2|IsHidden=T|Text=10%|Name=P1
|RECORD=41|OwnerIndex=588|IndexInSheet=7|OwnerPartId=-1|Location.X=186|Location.Y=354|Location.Y_Frac=48252|Color=8388608|FontID=2|IsHidden=T|Text=85C|Name=MAXTEMP
|RECORD=41|OwnerIndex=588|IndexInSheet=8|OwnerPartId=-1|Location.X=186|Location.Y=354|Location.Y_Frac=48252|Color=8388608|FontID=2|IsHidden=T|Text=-55C|Name=MINTEMP
|RECORD=41|OwnerIndex=588|IndexInSheet=9|OwnerPartId=-1|Location.X=186|Location.Y=354|Location.Y_Frac=48252|Color=8388608|FontID=2|IsHidden=T|Name=OTHER
|RECORD=41|OwnerIndex=588|IndexInSheet=10|OwnerPartId=-1|Location.X=186|Location.Y=354|Location.Y_Frac=48252|Color=8388608|FontID=2|IsHidden=T|Text=25V|Name=P2
|RECORD=41|OwnerIndex=588|IndexInSheet=11|OwnerPartId=-1|Location.X=186|Location.Y=354|Location.Y_Frac=48252|Color=8388608|FontID=2|IsHidden=T|Text=X5R|Name=P3
|RECORD=41|OwnerIndex=588|IndexInSheet=12|OwnerPartId=-1|Location.X=186|Location.Y=354|Location.Y_Frac=48252|Color=8388608|FontID=2|IsHidden=T|Text=0805|Name=Size
|RECORD=41|OwnerIndex=588|IndexInSheet=13|OwnerPartId=-1|Location.X=186|Location.Y=354|Location.Y_Frac=48252|Color=8388608|FontID=2|IsHidden=T|Name=SUB
|RECORD=41|OwnerIndex=588|IndexInSheet=14|OwnerPartId=-1|Location.X=186|Location.Y=354|Location.Y_Frac=48252|Color=8388608|FontID=1|IsHidden=T|Text=CAP, CER, 10.UF, 10V, 10%, X5R, 0805|Name=DESC
|RECORD=41|OwnerIndex=588|IndexInSheet=15|OwnerPartId=-1|Location.X=186|Location.Y=353|Location.Y_Frac=98252|Color=8388608|FontID=1|IsHidden=T|Text=MOUSER|Name=Supplier 1|ReadOnlyState=1
|RECORD=41|OwnerIndex=588|IndexInSheet=16|OwnerPartId=-1|Location.X=186|Location.Y=353|Location.Y_Frac=98252|Color=8388608|FontID=1|IsHidden=T|Text=963-TMK212BBJ106KG-T|Name=Supplier Part Number 1|ReadOnlyState=1
|RECORD=41|OwnerIndex=588|IndexInSheet=17|OwnerPartId=-1|Location.X=210|Location.Y=310|Color=8388608|FontID=2|Text=10uF|Name=VALUE
|RECORD=2|OwnerIndex=588|OwnerPartId=1|FormalType=1|Electrical=4|PinConglomerate=35|PinLength=10|Location.X=200|Location.Y=310|Name=2|Designator=2|SwapIdPin=2|SwapIDPart=1|PinPropagationDelay=0.000000E+000
|RECORD=2|OwnerIndex=588|OwnerPartId=1|FormalType=1|Electrical=4|PinConglomerate=33|PinLength=10|Location.X=200|Location.Y=320|Name=1|Designator=1|SwapIdPin=1|SwapIDPart=1|PinPropagationDelay=0.000000E+000
|RECORD=13|OwnerIndex=588|IsNotAccesible=T|IndexInSheet=20|OwnerPartId=1|Location.X=200|Location.Y=312|Location.Y_Frac=50000|Corner.X=200|Corner.Y=310|LineWidth=1|Color=16711680
|RECORD=13|OwnerIndex=588|IsNotAccesible=T|IndexInSheet=21|OwnerPartId=1|Location.X=200|Location.Y=320|Corner.X=200|Corner.Y=317|Corner.Y_Frac=50000|LineWidth=1|Color=16711680
|RECORD=13|OwnerIndex=588|IsNotAccesible=T|IndexInSheet=22|OwnerPartId=1|Location.X=205|Location.Y=312|Location.Y_Frac=50000|Corner.X=195|Corner.Y=312|Corner.Y_Frac=50000|LineWidth=1|Color=16711680
|RECORD=13|OwnerIndex=588|IsNotAccesible=T|IndexInSheet=23|OwnerPartId=1|Location.X=205|Location.Y=317|Location.Y_Frac=50000|Corner.X=195|Corner.Y=317|Corner.Y_Frac=50000|LineWidth=1|Color=16711680
|RECORD=41|OwnerIndex=588|IndexInSheet=24|OwnerPartId=-1|Location.X=186|Location.Y=353|Location.Y_Frac=98951|Color=8388608|FontID=1|IsHidden=T|Text=<VALENTIUM>|Name=VALENTIUM PART NUM
|RECORD=34|OwnerIndex=588|IndexInSheet=-1|OwnerPartId=-1|Location.X=210|Location.Y=320|Color=8388608|FontID=3|Text=C56|Name=Designator|ReadOnlyState=1
|RECORD=41|OwnerIndex=588|IndexInSheet=-1|OwnerPartId=-1|Location.X=207|Location.X_Frac=50000|Location.Y=275|Color=8388608|FontID=2|IsHidden=T|Text=CAP_0805_10UF_25V|Name=Comment
|RECORD=44|OwnerIndex=588
|RECORD=45|OwnerIndex=618|IndexInSheet=-1|Description=Chip Capacitor, 0805, 2-Leads, Body 2.00x1.25mm, IPC Medium Density|UseComponentLibrary=T|ModelName=CAPC2012X14N|ModelType=PCBLIB|DatafileCount=1|ModelDatafileEntity0=CAPC2012X14N|ModelDatafileKind0=PCBLib|IsCurrent=T|DatalinksLocked=T|DatabaseDatalinksLocked=T|IntegratedModel=T|DatabaseModel=T
|RECORD=46|OwnerIndex=619
|RECORD=48|OwnerIndex=619
|RECORD=1|LibReference=BNO080|ComponentDescription=MOD, IMU, 5.2X3.8, SMT|PartCount=2|DisplayModeCount=1|IndexInSheet=108|OwnerPartId=-1|Location.X=510|Location.Y=290|CurrentPartId=1|LibraryPath=*|SourceLibraryName=Modules.IntLib|TargetFileName=*|AreaColor=11599871|Color=128|PartIDLocked=F|DesignItemId=BNO080|AllPinCount=28
|RECORD=41|OwnerIndex=622|OwnerPartId=-1|Location.X=510|Location.Y=290|Color=8388608|FontID=2|IsHidden=T|Text=BNO080|Name=MFG PART NUM
|RECORD=41|OwnerIndex=622|IndexInSheet=1|OwnerPartId=-1|Location.X=510|Location.Y=290|Color=8388608|FontID=2|IsHidden=T|Text=10/21/2013|Name=MODIFY DATE
|RECORD=41|OwnerIndex=622|IndexInSheet=2|OwnerPartId=-1|Location.X=509|Location.X_Frac=99996|Location.Y=289|Location.Y_Frac=99996|Color=8388608|FontID=2|IsHidden=T|Text=HILLCREST|Name=MFG NAME
|RECORD=41|OwnerIndex=622|IndexInSheet=3|OwnerPartId=-1|Location.X=368|Location.Y=318|Color=8388608|FontID=2|IsHidden=T|Text=MOD|Name=CATEGORY
|RECORD=41|OwnerIndex=622|IndexInSheet=4|OwnerPartId=-1|Location.X=368|Location.Y=318|Color=8388608|FontID=2|IsHidden=T|Name=DATE
|RECORD=41|OwnerIndex=622|IndexInSheet=5|OwnerPartId=-1|Location.X=508|Location.Y=368|Color=8388608|FontID=2|IsHidden=T|Text=+85C|Name=MAXTEMP
|RECORD=41|OwnerIndex=622|IndexInSheet=6|OwnerPartId=-1|Location.X=508|Location.Y=368|Color=8388608|FontID=2|IsHidden=T|Text=-40C|Name=MINTEMP
|RECORD=41|OwnerIndex=622|IndexInSheet=7|OwnerPartId=-1|Location.X=508|Location.Y=368|Color=8388608|FontID=2|IsHidden=T|Text=IMU|Name=OTHER
|RECORD=41|OwnerIndex=622|IndexInSheet=8|OwnerPartId=-1|Location.X=508|Location.Y=368|Color=8388608|FontID=2|IsHidden=T|Name=P1
|RECORD=41|OwnerIndex=622|IndexInSheet=9|OwnerPartId=-1|Location.X=508|Location.Y=368|Color=8388608|FontID=2|IsHidden=T|Name=P2
|RECORD=41|OwnerIndex=622|IndexInSheet=10|OwnerPartId=-1|Location.X=508|Location.Y=368|Color=8388608|FontID=2|IsHidden=T|Name=P3
|RECORD=41|OwnerIndex=622|IndexInSheet=11|OwnerPartId=-1|Location.X=508|Location.Y=368|Color=8388608|FontID=2|IsHidden=T|Text=5.2X3.8|Name=SIZE
|RECORD=41|OwnerIndex=622|IndexInSheet=12|OwnerPartId=-1|Location.X=508|Location.Y=368|Color=8388608|FontID=2|IsHidden=T|Name=SUB
|RECORD=41|OwnerIndex=622|IndexInSheet=13|OwnerPartId=-1|Location.X=508|Location.Y=289|Color=8388608|FontID=1|IsHidden=T|Text=*|Name=SHEETPART
|RECORD=41|OwnerIndex=622|IndexInSheet=14|OwnerPartId=-1|Location.X=508|Location.Y=380|Color=8388608|FontID=1|IsHidden=T|Text=MOD, IMU, 5.2X3.8, SMT|Name=DESC
|RECORD=41|OwnerIndex=622|IndexInSheet=15|OwnerPartId=-1|Location.X=508|Location.Y=380|Color=8388608|FontID=1|IsHidden=T|Text=<V PART NUM>|Name=VELENTIUM PART NUM
|RECORD=41|OwnerIndex=622|IndexInSheet=16|OwnerPartId=-1|Location.X=408|Location.Y=382|Color=8388608|FontID=1|IsHidden=T|Text=Digi-Key|Name=Supplier 1|ReadOnlyState=3
|RECORD=41|OwnerIndex=622|IndexInSheet=17|OwnerPartId=-1|Location.X=408|Location.Y=382|Color=8388608|FontID=1|IsHidden=T|Text=1888-1000-1-ND|Name=Supplier Part Number 1|ReadOnlyState=3
|RECORD=41|OwnerIndex=622|IndexInSheet=18|OwnerPartId=-1|Location.X=440|Location.Y=208|Color=8388608|FontID=2|Text=BNO080|Name=VALUE
|RECORD=14|OwnerIndex=622|IsNotAccesible=T|IndexInSheet=19|OwnerPartId=1|Location.X=440|Location.Y=220|Corner.X=570|Corner.Y=370|Color=128|AreaColor=11599871|IsSolid=T
|RECORD=2|OwnerIndex=622|OwnerPartId=1|FormalType=1|Electrical=4|PinConglomerate=58|PinLength=30|Location.X=440|Location.Y=360|Name=NC|Designator=1|SwapIDPart=Ž&Ž||PinPropagationDelay=0.000000E+000
|RECORD=2|OwnerIndex=622|OwnerPartId=1|FormalType=1|Electrical=4|PinConglomerate=58|PinLength=30|Location.X=440|Location.Y=350|Name=GND|Designator=2|SwapIDPart=Ž&Ž||PinPropagationDelay=0.000000E+000
|RECORD=2|OwnerIndex=622|OwnerPartId=1|FormalType=1|Electrical=4|PinConglomerate=58|PinLength=30|Location.X=440|Location.Y=340|Name=VDD|Designator=3|SwapIDPart=Ž&Ž||PinPropagationDelay=0.000000E+000
|RECORD=2|OwnerIndex=622|OwnerPartId=1|FormalType=1|Electrical=4|PinConglomerate=58|PinLength=30|Location.X=440|Location.Y=330|Name=BOOTN|Designator=4|SwapIDPart=Ž&Ž||PinPropagationDelay=0.000000E+000
|RECORD=2|OwnerIndex=622|OwnerPartId=1|FormalType=1|Electrical=4|PinConglomerate=58|PinLength=30|Location.X=440|Location.Y=320|Name=PS1|Designator=5|SwapIDPart=Ž&Ž||PinPropagationDelay=0.000000E+000
|RECORD=2|OwnerIndex=622|OwnerPartId=1|FormalType=1|Electrical=4|PinConglomerate=58|PinLength=30|Location.X=440|Location.Y=310|Name=PS0/WAKE|Designator=6|SwapIDPart=Ž&Ž||PinPropagationDelay=0.000000E+000
|RECORD=2|OwnerIndex=622|OwnerPartId=1|FormalType=1|Electrical=4|PinConglomerate=58|PinLength=30|Location.X=440|Location.Y=300|Name=NC|Designator=7|SwapIDPart=Ž&Ž||PinPropagationDelay=0.000000E+000
|RECORD=2|OwnerIndex=622|OwnerPartId=1|FormalType=1|Electrical=4|PinConglomerate=58|PinLength=30|Location.X=440|Location.Y=290|Name=NC|Designator=8|SwapIDPart=Ž&Ž||PinPropagationDelay=0.000000E+000
|RECORD=2|OwnerIndex=622|OwnerPartId=1|FormalType=1|Electrical=4|PinConglomerate=58|PinLength=30|Location.X=440|Location.Y=280|Name=CAP|Designator=9|SwapIDPart=Ž&Ž||PinPropagationDelay=0.000000E+000
|RECORD=2|OwnerIndex=622|OwnerPartId=1|FormalType=1|Electrical=4|PinConglomerate=58|PinLength=30|Location.X=440|Location.Y=270|Name=CLKSEL0|Designator=10|SwapIDPart=Ž&Ž||PinPropagationDelay=0.000000E+000
|RECORD=2|OwnerIndex=622|OwnerPartId=1|FormalType=1|Electrical=4|PinConglomerate=58|PinLength=30|Location.X=440|Location.Y=260|Name=NRST|Designator=11|SwapIDPart=Ž&Ž||PinPropagationDelay=0.000000E+000
|RECORD=2|OwnerIndex=622|OwnerPartId=1|FormalType=1|Electrical=4|PinConglomerate=58|PinLength=30|Location.X=440|Location.Y=250|Name=NC|Designator=12|SwapIDPart=Ž&Ž||PinPropagationDelay=0.000000E+000
|RECORD=2|OwnerIndex=622|OwnerPartId=1|FormalType=1|Electrical=4|PinConglomerate=58|PinLength=30|Location.X=440|Location.Y=240|Name=NC|Designator=13|SwapIDPart=Ž&Ž||PinPropagationDelay=0.000000E+000
|RECORD=2|OwnerIndex=622|OwnerPartId=1|FormalType=1|Electrical=4|PinConglomerate=58|PinLength=30|Location.X=440|Location.Y=230|Name=H_INTN|Designator=14|SwapIDPart=Ž&Ž||PinPropagationDelay=0.000000E+000
|RECORD=2|OwnerIndex=622|OwnerPartId=1|FormalType=1|Electrical=4|PinConglomerate=56|PinLength=30|Location.X=570|Location.Y=230|Name=ENV_SCL|Designator=15|SwapIDPart=Ž&Ž||PinPropagationDelay=0.000000E+000
|RECORD=2|OwnerIndex=622|OwnerPartId=1|FormalType=1|Electrical=4|PinConglomerate=56|PinLength=30|Location.X=570|Location.Y=240|Name=ENV_SDA|Designator=16|SwapIDPart=Ž&Ž||PinPropagationDelay=0.000000E+000
|RECORD=2|OwnerIndex=622|OwnerPartId=1|FormalType=1|Electrical=4|PinConglomerate=56|PinLength=30|Location.X=570|Location.Y=250|Name=SA0/H_MOSI|Designator=17|SwapIDPart=Ž&Ž||PinPropagationDelay=0.000000E+000
|RECORD=2|OwnerIndex=622|OwnerPartId=1|FormalType=1|Electrical=4|PinConglomerate=56|PinLength=30|Location.X=570|Location.Y=260|Name=H_CSN|Designator=18|SwapIDPart=Ž&Ž||PinPropagationDelay=0.000000E+000
|RECORD=2|OwnerIndex=622|OwnerPartId=1|FormalType=1|Electrical=4|PinConglomerate=56|PinLength=30|Location.X=570|Location.Y=270|Name=H_SCL/SCK/RX|Designator=19|SwapIDPart=Ž&Ž||PinPropagationDelay=0.000000E+000
|RECORD=2|OwnerIndex=622|OwnerPartId=1|FormalType=1|Electrical=4|PinConglomerate=56|PinLength=30|Location.X=570|Location.Y=280|Name=H_SDA/H_MISO/TX|Designator=20|SwapIDPart=Ž&Ž||PinPropagationDelay=0.000000E+000
|RECORD=2|OwnerIndex=622|OwnerPartId=1|FormalType=1|Electrical=4|PinConglomerate=56|PinLength=30|Location.X=570|Location.Y=290|Name=NC|Designator=21|SwapIDPart=Ž&Ž||PinPropagationDelay=0.000000E+000
|RECORD=2|OwnerIndex=622|OwnerPartId=1|FormalType=1|Electrical=4|PinConglomerate=56|PinLength=30|Location.X=570|Location.Y=300|Name=NC|Designator=22|SwapIDPart=Ž&Ž||PinPropagationDelay=0.000000E+000
|RECORD=2|OwnerIndex=622|OwnerPartId=1|FormalType=1|Electrical=4|PinConglomerate=56|PinLength=30|Location.X=570|Location.Y=310|Name=NC|Designator=23|SwapIDPart=Ž&Ž||PinPropagationDelay=0.000000E+000
|RECORD=2|OwnerIndex=622|OwnerPartId=1|FormalType=1|Electrical=4|PinConglomerate=56|PinLength=30|Location.X=570|Location.Y=320|Name=NC|Designator=24|SwapIDPart=Ž&Ž||PinPropagationDelay=0.000000E+000
|RECORD=2|OwnerIndex=622|OwnerPartId=1|FormalType=1|Electrical=4|PinConglomerate=56|PinLength=30|Location.X=570|Location.Y=330|Name=GND|Designator=25|SwapIDPart=Ž&Ž||PinPropagationDelay=0.000000E+000
|RECORD=2|OwnerIndex=622|OwnerPartId=1|FormalType=1|Electrical=4|PinConglomerate=56|PinLength=30|Location.X=570|Location.Y=340|Name=XOUT32/CLKSEL1|Designator=26|SwapIDPart=Ž&Ž||PinPropagationDelay=0.000000E+000
|RECORD=2|OwnerIndex=622|OwnerPartId=1|FormalType=1|Electrical=4|PinConglomerate=56|PinLength=30|Location.X=570|Location.Y=350|Name=XIN32|Designator=27|SwapIDPart=Ž&Ž||PinPropagationDelay=0.000000E+000
|RECORD=2|OwnerIndex=622|OwnerPartId=1|FormalType=1|Electrical=4|PinConglomerate=56|PinLength=30|Location.X=570|Location.Y=360|Name=VDDIO|Designator=28|SwapIDPart=Ž&Ž||PinPropagationDelay=0.000000E+000
|RECORD=34|OwnerIndex=622|IndexInSheet=-1|OwnerPartId=-1|Location.X=440|Location.Y=370|Color=8388608|FontID=3|Text=U8|Name=Designator|ReadOnlyState=1
|RECORD=41|OwnerIndex=622|IndexInSheet=-1|OwnerPartId=-1|Location.X=620|Location.Y=290|Color=8388608|FontID=2|IsHidden=T|Text=BNO080|Name=Comment
|RECORD=44|OwnerIndex=622
|RECORD=45|OwnerIndex=701|IndexInSheet=-1|UseComponentLibrary=T|ModelName=LGA-28|ModelType=PCBLIB|DatafileCount=1|ModelDatafileEntity0=LGA-28|ModelDatafileKind0=PCBLib|IsCurrent=T|DatalinksLocked=T|DatabaseDatalinksLocked=T|IntegratedModel=T|DatabaseModel=T
|RECORD=46|OwnerIndex=702
|RECORD=48|OwnerIndex=702
|RECORD=1|LibReference=MC306|ComponentDescription=XTAL, 32.768KHZ, 6PF LOAD CAP, SMD, ROHS|PartCount=2|DisplayModeCount=1|IndexInSheet=109|OwnerPartId=-1|Location.X=870|Location.Y=350|IsMirrored=T|Orientation=3|CurrentPartId=1|SourceLibraryName=Miscellaneous.IntLib|TargetFileName=*|AreaColor=11599871|Color=128|PartIDLocked=F|DesignItemId=MC306|AllPinCount=4
|RECORD=41|OwnerIndex=705|OwnerPartId=-1|Location.X=818|Location.Y=370|Color=8388608|FontID=2|IsHidden=T|Text=XTAL|Name=CATEGORY|IsMirrored=T
|RECORD=41|OwnerIndex=705|IndexInSheet=1|OwnerPartId=-1|Location.X=818|Location.Y=370|Color=8388608|FontID=2|IsHidden=T|Text=ABRACON CORPORATION|Name=MFG NAME|IsMirrored=T
|RECORD=41|OwnerIndex=705|IndexInSheet=2|OwnerPartId=-1|Location.X=818|Location.Y=370|Color=8388608|FontID=2|IsHidden=T|Text=MC-306 32.768K-E3:ROHS|Name=MFG PART NUM|IsMirrored=T
|RECORD=41|OwnerIndex=705|IndexInSheet=3|OwnerPartId=-1|Location.X=818|Location.Y=370|Color=8388608|FontID=2|IsHidden=T|Name=DATE|IsMirrored=T
|RECORD=41|OwnerIndex=705|IndexInSheet=4|OwnerPartId=-1|Location.X=818|Location.Y=370|Color=8388608|FontID=2|IsHidden=T|Text=9/5/2013|Name=MODIFY DATE|IsMirrored=T
|RECORD=41|OwnerIndex=705|IndexInSheet=5|OwnerPartId=-1|Location.X=818|Location.Y=370|Color=8388608|FontID=2|IsHidden=T|Text=85C|Name=MAXTEMP|IsMirrored=T
|RECORD=41|OwnerIndex=705|IndexInSheet=6|OwnerPartId=-1|Location.X=818|Location.Y=370|Color=8388608|FontID=2|IsHidden=T|Text=-40C|Name=MINTEMP|IsMirrored=T
|RECORD=41|OwnerIndex=705|IndexInSheet=7|OwnerPartId=-1|Location.X=818|Location.Y=370|Color=8388608|FontID=2|IsHidden=T|Text=6PF|Name=P1|IsMirrored=T
|RECORD=41|OwnerIndex=705|IndexInSheet=8|OwnerPartId=-1|Location.X=818|Location.Y=370|Color=8388608|FontID=2|IsHidden=T|Text=20PPM|Name=P2|IsMirrored=T
|RECORD=41|OwnerIndex=705|IndexInSheet=9|OwnerPartId=-1|Location.X=818|Location.Y=370|Color=8388608|FontID=2|IsHidden=T|Text=FUNDAMENTAL|Name=P3|IsMirrored=T
|RECORD=41|OwnerIndex=705|IndexInSheet=10|OwnerPartId=-1|Location.X=818|Location.Y=370|Color=8388608|FontID=2|IsHidden=T|Name=SUB|IsMirrored=T
|RECORD=41|OwnerIndex=705|IndexInSheet=11|OwnerPartId=-1|Location.X=818|Location.Y=370|Color=8388608|FontID=2|IsHidden=T|Text=Digi-Key|Name=Supplier 1|ReadOnlyState=3|IsMirrored=T
|RECORD=41|OwnerIndex=705|IndexInSheet=12|OwnerPartId=-1|Location.X=818|Location.Y=370|Color=8388608|FontID=2|IsHidden=T|Text=SER2417CT-ND|Name=Supplier Part Number 1|ReadOnlyState=3|IsMirrored=T
|RECORD=41|OwnerIndex=705|IndexInSheet=13|OwnerPartId=-1|Location.X=818|Location.Y=370|Color=8388608|FontID=2|IsHidden=T|Text=MC306, 3.8X8.00X2.54MM|Name=OTHER|IsMirrored=T
|RECORD=41|OwnerIndex=705|IndexInSheet=14|OwnerPartId=-1|Location.X=818|Location.Y=370|Color=8388608|FontID=2|IsHidden=T|Text=4-SOJ|Name=SIZE|IsMirrored=T
|RECORD=41|OwnerIndex=705|IndexInSheet=15|OwnerPartId=-1|Location.X=818|Location.Y=370|Color=8388608|FontID=1|IsHidden=T|Text=*|Name=SHEETPART|IsMirrored=T
|RECORD=41|OwnerIndex=705|IndexInSheet=16|OwnerPartId=-1|Location.X=818|Location.Y=370|Color=8388608|FontID=1|IsHidden=T|Text=XTAL, <VAL>, P1, P2, P3, EIA, OTHER|Name=DESC|IsMirrored=T
|RECORD=41|OwnerIndex=705|IndexInSheet=17|OwnerPartId=-1|Location.X=839|Location.Y=308|Color=8388608|FontID=2|Text=32.768kHz|Name=VALUE|IsMirrored=T
|RECORD=14|OwnerIndex=705|IsNotAccesible=T|IndexInSheet=18|OwnerPartId=1|Location.X=840|Location.Y=320|Corner.X=860|Corner.Y=370|LineWidth=1|AreaColor=16777215|IsSolid=T|Transparent=T
|RECORD=13|OwnerIndex=705|IsNotAccesible=T|IndexInSheet=19|OwnerPartId=1|Location.X=846|Location.Y=359|Corner.X=846|Corner.Y=341|LineWidth=1|Color=16711680
|RECORD=13|OwnerIndex=705|IsNotAccesible=T|IndexInSheet=20|OwnerPartId=1|Location.X=854|Location.Y=359|Corner.X=854|Corner.Y=341|LineWidth=1|Color=16711680
|RECORD=13|OwnerIndex=705|IsNotAccesible=T|IndexInSheet=21|OwnerPartId=1|Location.X=854|Location.Y=341|Corner.X=846|Corner.Y=341|LineWidth=1|Color=16711680
|RECORD=13|OwnerIndex=705|IsNotAccesible=T|IndexInSheet=22|OwnerPartId=1|Location.X=854|Location.Y=359|Corner.X=846|Corner.Y=359|LineWidth=1|Color=16711680
|RECORD=2|OwnerIndex=705|OwnerPartId=1|FormalType=1|Electrical=4|PinConglomerate=48|PinLength=20|Location.X=860|Location.Y=350|Name=4|Designator=4|SwapIdPin=1|SwapIDPart=0|PinPropagationDelay=0.000000E+000
|RECORD=2|OwnerIndex=705|OwnerPartId=1|FormalType=1|Electrical=4|PinConglomerate=50|PinLength=20|Location.X=840|Location.Y=350|Name=1|Designator=1|SwapIdPin=4|SwapIDPart=0|PinPropagationDelay=0.000000E+000
|RECORD=2|OwnerIndex=705|OwnerPartId=1|FormalType=1|Electrical=4|PinConglomerate=48|PinLength=20|Location.X=860|Location.Y=330|Name=3|Designator=3|SwapIdPin=2|SwapIDPart=0|PinPropagationDelay=0.000000E+000
|RECORD=2|OwnerIndex=705|OwnerPartId=1|FormalType=1|Electrical=4|PinConglomerate=50|PinLength=20|Location.X=840|Location.Y=330|Name=2|Designator=2|SwapIdPin=3|SwapIDPart=0|PinPropagationDelay=0.000000E+000
|RECORD=6|OwnerIndex=705|IsNotAccesible=T|IndexInSheet=27|OwnerPartId=1|LineWidth=1|Color=16711680|LocationCount=2|X1=843|Y1=359|X2=843|Y2=341
|RECORD=6|OwnerIndex=705|IsNotAccesible=T|IndexInSheet=28|OwnerPartId=1|LineWidth=1|Color=16711680|LocationCount=2|X1=843|Y1=350|X2=840|Y2=350
|RECORD=6|OwnerIndex=705|IsNotAccesible=T|IndexInSheet=29|OwnerPartId=1|LineWidth=1|Color=16711680|LocationCount=2|X1=857|Y1=341|X2=857|Y2=359
|RECORD=6|OwnerIndex=705|IsNotAccesible=T|IndexInSheet=30|OwnerPartId=1|LineWidth=1|Color=16711680|LocationCount=2|X1=857|Y1=350|X2=860|Y2=350
|RECORD=41|OwnerIndex=705|IndexInSheet=31|OwnerPartId=-1|Location.X=818|Location.Y=370|Color=8388608|FontID=1|IsHidden=T|Text=<VALENTIUM>|Name=VALENTIUM PART NUM|IsMirrored=T
|RECORD=34|OwnerIndex=705|IndexInSheet=-1|OwnerPartId=-1|Location.X=839|Location.Y=370|Color=8388608|FontID=3|Text=X1|Name=Designator|ReadOnlyState=1
|RECORD=41|OwnerIndex=705|IndexInSheet=-1|OwnerPartId=-1|Location.X=818|Location.Y=370|Color=8388608|FontID=2|IsHidden=T|Text=MC306|Name=Comment
|RECORD=44|OwnerIndex=705
|RECORD=45|OwnerIndex=744|IndexInSheet=-1|Description=Footprint not found|UseComponentLibrary=T|ModelName=SM8|ModelType=PCBLIB|DatafileCount=1|ModelDatafileEntity0=SM8|ModelDatafileKind0=PCBLib|IsCurrent=T|DatalinksLocked=T|DatabaseDatalinksLocked=T|IntegratedModel=T|DatabaseModel=T
|RECORD=46|OwnerIndex=745
|RECORD=48|OwnerIndex=745
|RECORD=22|IndexInSheet=110|OwnerPartId=-1|Location.X=820|Location.Y=330|Color=255|Orientation=1|Symbol=Thin Cross|IsActive=T|SuppressAll=T
|RECORD=22|IndexInSheet=111|OwnerPartId=-1|Location.X=880|Location.Y=330|Color=255|Orientation=1|Symbol=Thin Cross|IsActive=T|SuppressAll=T
|RECORD=1|LibReference=CAP_0603_22PF_50V|ComponentDescription=CAP, CER, 22.PF, 50V, 5%, NPO, 0603|PartCount=2|DisplayModeCount=1|IndexInSheet=112|OwnerPartId=-1|Location.X=780|Location.Y=350|Orientation=2|CurrentPartId=1|LibraryPath=*|SourceLibraryName=Capacitors.IntLib|TargetFileName=*|AreaColor=11599871|Color=128|PartIDLocked=F|DesignItemId=CAP_0603_22PF_50V|AllPinCount=2
|RECORD=41|OwnerIndex=750|OwnerPartId=-1|Location.X=754|Location.Y=332|Color=8388608|FontID=2|IsHidden=T|Text=CAP, CER|Name=CATEGORY
|RECORD=41|OwnerIndex=750|IndexInSheet=1|OwnerPartId=-1|Location.X=754|Location.Y=332|Color=8388608|FontID=2|IsHidden=T|Text=KEMET|Name=MFG NAME
|RECORD=41|OwnerIndex=750|IndexInSheet=2|OwnerPartId=-1|Location.X=754|Location.Y=332|Color=8388608|FontID=2|IsHidden=T|Text=C0603C220J5GACTU|Name=MFG PART NUM
|RECORD=41|OwnerIndex=750|IndexInSheet=3|OwnerPartId=-1|Location.X=754|Location.Y=332|Color=8388608|FontID=2|IsHidden=T|Text=10/23/2013|Name=MODIFY DATE
|RECORD=41|OwnerIndex=750|IndexInSheet=4|OwnerPartId=-1|Location.X=754|Location.Y=332|Color=8388608|FontID=2|IsHidden=T|Text=7/25/2013|Name=Date
|RECORD=41|OwnerIndex=750|IndexInSheet=5|OwnerPartId=-1|Location.X=754|Location.Y=332|Color=8388608|FontID=2|IsHidden=T|Text=*|Name=SHEETPART
|RECORD=41|OwnerIndex=750|IndexInSheet=6|OwnerPartId=-1|Location.X=754|Location.Y=332|Color=8388608|FontID=2|IsHidden=T|Text=5%|Name=P1
|RECORD=41|OwnerIndex=750|IndexInSheet=7|OwnerPartId=-1|Location.X=754|Location.Y=332|Color=8388608|FontID=2|IsHidden=T|Text=125C|Name=MAXTEMP
|RECORD=41|OwnerIndex=750|IndexInSheet=8|OwnerPartId=-1|Location.X=754|Location.Y=332|Color=8388608|FontID=2|IsHidden=T|Text=-55C|Name=MINTEMP
|RECORD=41|OwnerIndex=750|IndexInSheet=9|OwnerPartId=-1|Location.X=754|Location.Y=332|Color=8388608|FontID=2|IsHidden=T|Name=OTHER
|RECORD=41|OwnerIndex=750|IndexInSheet=10|OwnerPartId=-1|Location.X=754|Location.Y=332|Color=8388608|FontID=2|IsHidden=T|Text=50V|Name=P2
|RECORD=41|OwnerIndex=750|IndexInSheet=11|OwnerPartId=-1|Location.X=754|Location.Y=332|Color=8388608|FontID=2|IsHidden=T|Text=NP0|Name=P3
|RECORD=41|OwnerIndex=750|IndexInSheet=12|OwnerPartId=-1|Location.X=754|Location.Y=332|Color=8388608|FontID=2|IsHidden=T|Text=0603|Name=Size
|RECORD=41|OwnerIndex=750|IndexInSheet=13|OwnerPartId=-1|Location.X=754|Location.Y=332|Color=8388608|FontID=2|IsHidden=T|Name=SUB
|RECORD=41|OwnerIndex=750|IndexInSheet=14|OwnerPartId=-1|Location.X=754|Location.Y=332|Color=8388608|FontID=2|IsHidden=T|Text=Digi-Key|Name=Supplier 1|ReadOnlyState=3
|RECORD=41|OwnerIndex=750|IndexInSheet=15|OwnerPartId=-1|Location.X=754|Location.Y=332|Color=8388608|FontID=2|IsHidden=T|Text=399-1053-1-ND|Name=Supplier Part Number 1|ReadOnlyState=3
|RECORD=41|OwnerIndex=750|IndexInSheet=16|OwnerPartId=-1|Location.X=754|Location.Y=332|Color=8388608|FontID=1|IsHidden=T|Text=CAP, CER, 22.PF, 50V, 5%, NPO, 0603|Name=DESC
|RECORD=41|OwnerIndex=750|IndexInSheet=17|OwnerPartId=-1|Location.X=766|Location.Y=295|Color=8388608|FontID=2|Text=22pF|Name=VALUE
|RECORD=2|OwnerIndex=750|OwnerPartId=1|FormalType=1|Electrical=4|PinConglomerate=33|PinLength=10|Location.X=760|Location.Y=320|Name=2|Designator=2|SwapIdPin=2|SwapIDPart=1|PinPropagationDelay=0.000000E+000
|RECORD=2|OwnerIndex=750|OwnerPartId=1|FormalType=1|Electrical=4|PinConglomerate=35|PinLength=10|Location.X=760|Location.Y=310|Name=1|Designator=1|SwapIdPin=1|SwapIDPart=1|PinPropagationDelay=0.000000E+000
|RECORD=13|OwnerIndex=750|IsNotAccesible=T|IndexInSheet=20|OwnerPartId=1|Location.X=760|Location.Y=317|Location.Y_Frac=50000|Corner.X=760|Corner.Y=320|LineWidth=1|Color=16711680
|RECORD=13|OwnerIndex=750|IsNotAccesible=T|IndexInSheet=21|OwnerPartId=1|Location.X=760|Location.Y=310|Corner.X=760|Corner.Y=312|Corner.Y_Frac=50000|LineWidth=1|Color=16711680
|RECORD=13|OwnerIndex=750|IsNotAccesible=T|IndexInSheet=22|OwnerPartId=1|Location.X=755|Location.Y=317|Location.Y_Frac=50000|Corner.X=765|Corner.Y=317|Corner.Y_Frac=50000|LineWidth=1|Color=16711680
|RECORD=13|OwnerIndex=750|IsNotAccesible=T|IndexInSheet=23|OwnerPartId=1|Location.X=755|Location.Y=312|Location.Y_Frac=50000|Corner.X=765|Corner.Y=312|Corner.Y_Frac=50000|LineWidth=1|Color=16711680
|RECORD=41|OwnerIndex=750|IndexInSheet=24|OwnerPartId=-1|Location.X=754|Location.Y=332|Color=8388608|FontID=1|IsHidden=T|Text=<VALENTIUM>|Name=VALENTIUM PART NUM
|RECORD=34|OwnerIndex=750|IndexInSheet=-1|OwnerPartId=-1|Location.X=766|Location.Y=307|Color=8388608|FontID=3|Text=C86|Name=Designator|ReadOnlyState=1
|RECORD=41|OwnerIndex=750|IndexInSheet=-1|OwnerPartId=-1|Location.X=754|Location.Y=332|Color=8388608|FontID=2|IsHidden=T|Text=CAP_0603_22PF_50V|Name=Comment|ReadOnlyState=1
|RECORD=44|OwnerIndex=750
|RECORD=45|OwnerIndex=780|IndexInSheet=-1|Description=Chip Capacitor, 0603, 2-Leads, Body 1.60x0.80mm, IPC Medium Density|UseComponentLibrary=T|ModelName=CAPC1608X10N|ModelType=PCBLIB|DatafileCount=1|ModelDatafileEntity0=CAPC1608X10N|ModelDatafileKind0=PCBLib|IsCurrent=T|DatalinksLocked=T|DatabaseDatalinksLocked=T|IntegratedModel=T|DatabaseModel=T
|RECORD=46|OwnerIndex=781
|RECORD=48|OwnerIndex=781
|RECORD=1|LibReference=CAP_0603_22PF_50V|ComponentDescription=CAP, CER, 22.PF, 50V, 5%, NPO, 0603|PartCount=2|DisplayModeCount=1|IndexInSheet=113|OwnerPartId=-1|Location.X=730|Location.Y=350|Orientation=2|CurrentPartId=1|LibraryPath=*|SourceLibraryName=Capacitors.IntLib|TargetFileName=*|AreaColor=11599871|Color=128|PartIDLocked=F|DesignItemId=CAP_0603_22PF_50V|AllPinCount=2
|RECORD=41|OwnerIndex=784|OwnerPartId=-1|Location.X=704|Location.Y=332|Color=8388608|FontID=2|IsHidden=T|Text=CAP, CER|Name=CATEGORY
|RECORD=41|OwnerIndex=784|IndexInSheet=1|OwnerPartId=-1|Location.X=704|Location.Y=332|Color=8388608|FontID=2|IsHidden=T|Text=KEMET|Name=MFG NAME
|RECORD=41|OwnerIndex=784|IndexInSheet=2|OwnerPartId=-1|Location.X=704|Location.Y=332|Color=8388608|FontID=2|IsHidden=T|Text=C0603C220J5GACTU|Name=MFG PART NUM
|RECORD=41|OwnerIndex=784|IndexInSheet=3|OwnerPartId=-1|Location.X=704|Location.Y=332|Color=8388608|FontID=2|IsHidden=T|Text=10/23/2013|Name=MODIFY DATE
|RECORD=41|OwnerIndex=784|IndexInSheet=4|OwnerPartId=-1|Location.X=704|Location.Y=332|Color=8388608|FontID=2|IsHidden=T|Text=7/25/2013|Name=Date
|RECORD=41|OwnerIndex=784|IndexInSheet=5|OwnerPartId=-1|Location.X=704|Location.Y=332|Color=8388608|FontID=2|IsHidden=T|Text=*|Name=SHEETPART
|RECORD=41|OwnerIndex=784|IndexInSheet=6|OwnerPartId=-1|Location.X=704|Location.Y=332|Color=8388608|FontID=2|IsHidden=T|Text=5%|Name=P1
|RECORD=41|OwnerIndex=784|IndexInSheet=7|OwnerPartId=-1|Location.X=704|Location.Y=332|Color=8388608|FontID=2|IsHidden=T|Text=125C|Name=MAXTEMP
|RECORD=41|OwnerIndex=784|IndexInSheet=8|OwnerPartId=-1|Location.X=704|Location.Y=332|Color=8388608|FontID=2|IsHidden=T|Text=-55C|Name=MINTEMP
|RECORD=41|OwnerIndex=784|IndexInSheet=9|OwnerPartId=-1|Location.X=704|Location.Y=332|Color=8388608|FontID=2|IsHidden=T|Name=OTHER
|RECORD=41|OwnerIndex=784|IndexInSheet=10|OwnerPartId=-1|Location.X=704|Location.Y=332|Color=8388608|FontID=2|IsHidden=T|Text=50V|Name=P2
|RECORD=41|OwnerIndex=784|IndexInSheet=11|OwnerPartId=-1|Location.X=704|Location.Y=332|Color=8388608|FontID=2|IsHidden=T|Text=NP0|Name=P3
|RECORD=41|OwnerIndex=784|IndexInSheet=12|OwnerPartId=-1|Location.X=704|Location.Y=332|Color=8388608|FontID=2|IsHidden=T|Text=0603|Name=Size
|RECORD=41|OwnerIndex=784|IndexInSheet=13|OwnerPartId=-1|Location.X=704|Location.Y=332|Color=8388608|FontID=2|IsHidden=T|Name=SUB
|RECORD=41|OwnerIndex=784|IndexInSheet=14|OwnerPartId=-1|Location.X=704|Location.Y=332|Color=8388608|FontID=2|IsHidden=T|Text=Digi-Key|Name=Supplier 1|ReadOnlyState=3
|RECORD=41|OwnerIndex=784|IndexInSheet=15|OwnerPartId=-1|Location.X=704|Location.Y=332|Color=8388608|FontID=2|IsHidden=T|Text=399-1053-1-ND|Name=Supplier Part Number 1|ReadOnlyState=3
|RECORD=41|OwnerIndex=784|IndexInSheet=16|OwnerPartId=-1|Location.X=704|Location.Y=332|Color=8388608|FontID=1|IsHidden=T|Text=CAP, CER, 22.PF, 50V, 5%, NPO, 0603|Name=DESC
|RECORD=41|OwnerIndex=784|IndexInSheet=17|OwnerPartId=-1|Location.X=716|Location.Y=295|Color=8388608|FontID=2|Text=22pF|Name=VALUE
|RECORD=2|OwnerIndex=784|OwnerPartId=1|FormalType=1|Electrical=4|PinConglomerate=33|PinLength=10|Location.X=710|Location.Y=320|Name=2|Designator=2|SwapIdPin=2|SwapIDPart=1|PinPropagationDelay=0.000000E+000
|RECORD=2|OwnerIndex=784|OwnerPartId=1|FormalType=1|Electrical=4|PinConglomerate=35|PinLength=10|Location.X=710|Location.Y=310|Name=1|Designator=1|SwapIdPin=1|SwapIDPart=1|PinPropagationDelay=0.000000E+000
|RECORD=13|OwnerIndex=784|IsNotAccesible=T|IndexInSheet=20|OwnerPartId=1|Location.X=710|Location.Y=317|Location.Y_Frac=50000|Corner.X=710|Corner.Y=320|LineWidth=1|Color=16711680
|RECORD=13|OwnerIndex=784|IsNotAccesible=T|IndexInSheet=21|OwnerPartId=1|Location.X=710|Location.Y=310|Corner.X=710|Corner.Y=312|Corner.Y_Frac=50000|LineWidth=1|Color=16711680
|RECORD=13|OwnerIndex=784|IsNotAccesible=T|IndexInSheet=22|OwnerPartId=1|Location.X=705|Location.Y=317|Location.Y_Frac=50000|Corner.X=715|Corner.Y=317|Corner.Y_Frac=50000|LineWidth=1|Color=16711680
|RECORD=13|OwnerIndex=784|IsNotAccesible=T|IndexInSheet=23|OwnerPartId=1|Location.X=705|Location.Y=312|Location.Y_Frac=50000|Corner.X=715|Corner.Y=312|Corner.Y_Frac=50000|LineWidth=1|Color=16711680
|RECORD=41|OwnerIndex=784|IndexInSheet=24|OwnerPartId=-1|Location.X=704|Location.Y=332|Color=8388608|FontID=1|IsHidden=T|Text=<VALENTIUM>|Name=VALENTIUM PART NUM
|RECORD=34|OwnerIndex=784|IndexInSheet=-1|OwnerPartId=-1|Location.X=716|Location.Y=307|Color=8388608|FontID=3|Text=C85|Name=Designator|ReadOnlyState=1
|RECORD=41|OwnerIndex=784|IndexInSheet=-1|OwnerPartId=-1|Location.X=704|Location.Y=332|Color=8388608|FontID=2|IsHidden=T|Text=CAP_0603_22PF_50V|Name=Comment|ReadOnlyState=1
|RECORD=44|OwnerIndex=784
|RECORD=45|OwnerIndex=814|IndexInSheet=-1|Description=Chip Capacitor, 0603, 2-Leads, Body 1.60x0.80mm, IPC Medium Density|UseComponentLibrary=T|ModelName=CAPC1608X10N|ModelType=PCBLIB|DatafileCount=1|ModelDatafileEntity0=CAPC1608X10N|ModelDatafileKind0=PCBLib|IsCurrent=T|DatalinksLocked=T|DatabaseDatalinksLocked=T|IntegratedModel=T|DatabaseModel=T
|RECORD=46|OwnerIndex=815
|RECORD=48|OwnerIndex=815
|RECORD=17|IndexInSheet=114|OwnerPartId=-1|Style=4|ShowNetName=T|Location.X=760|Location.Y=280|Orientation=3|Color=128|FontID=1|Text=GND
|RECORD=4|IndexInSheet=115|OwnerPartId=-1|Location.X=1180|Location.Y=1000|Color=8388608|FontID=4|Text=GPS UART
|RECORD=17|IndexInSheet=116|OwnerPartId=-1|ShowNetName=T|Location.X=890|Location.Y=730|Orientation=2|Color=255|FontID=1|Text=MAC_RX|IsCrossSheetConnector=T
|RECORD=17|IndexInSheet=117|OwnerPartId=-1|ShowNetName=T|Location.X=890|Location.Y=800|Orientation=2|Color=255|FontID=1|Text=MAC_TX|IsCrossSheetConnector=T
|RECORD=1|LibReference=Res3|ComponentDescription=Resistor|PartCount=2|DisplayModeCount=1|IndexInSheet=118|OwnerPartId=-1|Location.X=930|Location.Y=840|CurrentPartId=1|SourceLibraryName=Miscellaneous Devices.IntLib|TargetFileName=*|AreaColor=11599871|Color=128|PartIDLocked=F|DesignItemId=Res3|AllPinCount=2
|RECORD=2|OwnerIndex=822|OwnerPartId=1|FormalType=1|Electrical=4|PinConglomerate=34|PinLength=10|Location.X=930|Location.Y=830|Name=1|Designator=1|PinPropagationDelay=0.000000E+000
|RECORD=2|OwnerIndex=822|OwnerPartId=1|FormalType=1|Electrical=4|PinConglomerate=32|PinLength=10|Location.X=960|Location.Y=830|Name=2|Designator=2|PinPropagationDelay=0.000000E+000
|RECORD=6|OwnerIndex=822|IsNotAccesible=T|IndexInSheet=2|OwnerPartId=1|LineWidth=1|Color=16711680|LocationCount=7|X1=960|Y1=830|X2=957|Y2=833|X3=951|Y3=827|X4=945|Y4=833|X5=939|Y5=827|X6=933|Y6=833|X7=930|Y7=830
|RECORD=41|OwnerIndex=822|IndexInSheet=3|OwnerPartId=-1|Location.X=930|Location.Y=840|Color=8388608|FontID=1|IsHidden=T|Text=8-Jun-2000|Name=Published
|RECORD=41|OwnerIndex=822|IndexInSheet=4|OwnerPartId=-1|Location.X=930|Location.Y=840|Color=8388608|FontID=1|IsHidden=T|Text=29-May-2009|Name=LatestRevisionDate
|RECORD=41|OwnerIndex=822|IndexInSheet=5|OwnerPartId=-1|Location.X=930|Location.Y=840|Color=8388608|FontID=1|IsHidden=T|Text=IPC-7351 Footprint Added.|Name=LatestRevisionNote
|RECORD=41|OwnerIndex=822|IndexInSheet=6|OwnerPartId=-1|Location.X=930|Location.Y=840|Color=8388608|FontID=1|IsHidden=T|Text=J1-0603|Name=PackageReference
|RECORD=41|OwnerIndex=822|IndexInSheet=7|OwnerPartId=-1|Location.X=930|Location.Y=840|Color=8388608|FontID=1|IsHidden=T|Text=Altium Limited|Name=Publisher
|RECORD=41|OwnerIndex=822|IndexInSheet=8|OwnerPartId=-1|Location.X=930|Location.Y=840|Color=8388608|FontID=1|IsHidden=T|Text=Chip Resistor|Name=PackageDescription
|RECORD=41|OwnerIndex=822|IndexInSheet=9|OwnerPartId=-1|Location.X=900|Location.Y=820|Color=8388608|FontID=1|Text=0 Ohm|Name=Value
|RECORD=34|OwnerIndex=822|IndexInSheet=-1|OwnerPartId=-1|Location.X=929|Location.Y=834|Color=8388608|FontID=1|Text=R10|Name=Designator|ReadOnlyState=1
|RECORD=41|OwnerIndex=822|IndexInSheet=-1|OwnerPartId=-1|Location.X=929|Location.Y=816|Color=8388608|FontID=1|Text=GPS2TX|Name=Comment
|RECORD=44|OwnerIndex=822
|RECORD=45|OwnerIndex=837|IndexInSheet=-1|Description=Chip Resistor, Body 1.6x0.8mm, IPC High Density|UseComponentLibrary=T|ModelName=J1-0603|ModelType=PCBLIB|DatafileCount=1|ModelDatafileEntity0=J1-0603|ModelDatafileKind0=PCBLib|IsCurrent=T|DatalinksLocked=T|DatabaseDatalinksLocked=T|IntegratedModel=T|DatabaseModel=T
|RECORD=46|OwnerIndex=838
|RECORD=48|OwnerIndex=838
|RECORD=45|OwnerIndex=837|IndexInSheet=-1|Description=Chip Resistor, Body 3.2x2.5mm, IPC High Density|UseComponentLibrary=T|ModelName=14-1210|ModelType=PCBLIB|DatafileCount=1|ModelDatafileEntity0=14-1210|ModelDatafileKind0=PCBLib|DatalinksLocked=T|DatabaseDatalinksLocked=T|IntegratedModel=T|DatabaseModel=T
|RECORD=46|OwnerIndex=841
|RECORD=48|OwnerIndex=841
|RECORD=45|OwnerIndex=837|IndexInSheet=-1|Description=Chip Resistor, Body 5.0x2.5mm, IPC High Density|UseComponentLibrary=T|ModelName=12Z-2010|ModelType=PCBLIB|DatafileCount=1|ModelDatafileEntity0=12Z-2010|ModelDatafileKind0=PCBLib|DatalinksLocked=T|DatabaseDatalinksLocked=T|IntegratedModel=T|DatabaseModel=T
|RECORD=46|OwnerIndex=844
|RECORD=48|OwnerIndex=844
|RECORD=45|OwnerIndex=837|IndexInSheet=-1|Description=Chip Resistor, Body 6.3x3.2mm, IPC High Density|UseComponentLibrary=T|ModelName=RESC6332|ModelType=PCBLIB|DatafileCount=1|ModelDatafileEntity0=RESC6332|ModelDatafileKind0=PCBLib|DatalinksLocked=T|DatabaseDatalinksLocked=T|IntegratedModel=T|DatabaseModel=T
|RECORD=46|OwnerIndex=847
|RECORD=48|OwnerIndex=847
|RECORD=45|OwnerIndex=837|IndexInSheet=-1|Description=Resistor|UseComponentLibrary=T|ModelName=RESISTOR|ModelType=SIM|IsCurrent=T|DatalinksLocked=T|DatabaseDatalinksLocked=T|IntegratedModel=T|DatabaseModel=T
|RECORD=46|OwnerIndex=850
|RECORD=48|OwnerIndex=850
|RECORD=41|OwnerIndex=852|IndexInSheet=-1|OwnerPartId=-1|Color=8388608|FontID=1|Text=R|Name=Spice Prefix
|RECORD=41|OwnerIndex=852|IndexInSheet=-1|OwnerPartId=-1|Color=8388608|FontID=1|Text=@DESIGNATOR %1 %2 @VALUE|Name=Netlist
|RECORD=41|OwnerIndex=852|IndexInSheet=-1|OwnerPartId=-1|Color=8388608|FontID=1|Text=General|Name=Kind
|RECORD=41|OwnerIndex=852|IndexInSheet=-1|OwnerPartId=-1|Color=8388608|FontID=1|Text=Resistor|Name=SubKind
|RECORD=45|OwnerIndex=837|IndexInSheet=-1|UseComponentLibrary=T|ModelName=Res|ModelType=SI|IsCurrent=T|DatalinksLocked=T|DatabaseDatalinksLocked=T|IntegratedModel=T|DatabaseModel=T
|RECORD=46|OwnerIndex=857
|RECORD=48|OwnerIndex=857
|RECORD=41|OwnerIndex=859|IndexInSheet=-1|OwnerPartId=-1|Color=8388608|FontID=1|Text=Resistor|Name=Type
|RECORD=41|OwnerIndex=859|IndexInSheet=-1|OwnerPartId=-1|Color=8388608|FontID=1|Name=Tech
|RECORD=1|LibReference=Res3|ComponentDescription=Resistor|PartCount=2|DisplayModeCount=1|IndexInSheet=119|OwnerPartId=-1|Location.X=930|Location.Y=810|CurrentPartId=1|SourceLibraryName=Miscellaneous Devices.IntLib|TargetFileName=*|AreaColor=11599871|Color=128|PartIDLocked=F|DesignItemId=Res3|AllPinCount=2
|RECORD=2|OwnerIndex=862|OwnerPartId=1|FormalType=1|Electrical=4|PinConglomerate=34|PinLength=10|Location.X=930|Location.Y=800|Name=1|Designator=1|PinPropagationDelay=0.000000E+000
|RECORD=2|OwnerIndex=862|OwnerPartId=1|FormalType=1|Electrical=4|PinConglomerate=32|PinLength=10|Location.X=960|Location.Y=800|Name=2|Designator=2|PinPropagationDelay=0.000000E+000
|RECORD=6|OwnerIndex=862|IsNotAccesible=T|IndexInSheet=2|OwnerPartId=1|LineWidth=1|Color=16711680|LocationCount=7|X1=960|Y1=800|X2=957|Y2=803|X3=951|Y3=797|X4=945|Y4=803|X5=939|Y5=797|X6=933|Y6=803|X7=930|Y7=800
|RECORD=41|OwnerIndex=862|IndexInSheet=3|OwnerPartId=-1|Location.X=930|Location.Y=810|Color=8388608|FontID=1|IsHidden=T|Text=8-Jun-2000|Name=Published
|RECORD=41|OwnerIndex=862|IndexInSheet=4|OwnerPartId=-1|Location.X=930|Location.Y=810|Color=8388608|FontID=1|IsHidden=T|Text=29-May-2009|Name=LatestRevisionDate
|RECORD=41|OwnerIndex=862|IndexInSheet=5|OwnerPartId=-1|Location.X=930|Location.Y=810|Color=8388608|FontID=1|IsHidden=T|Text=IPC-7351 Footprint Added.|Name=LatestRevisionNote
|RECORD=41|OwnerIndex=862|IndexInSheet=6|OwnerPartId=-1|Location.X=930|Location.Y=810|Color=8388608|FontID=1|IsHidden=T|Text=J1-0603|Name=PackageReference
|RECORD=41|OwnerIndex=862|IndexInSheet=7|OwnerPartId=-1|Location.X=930|Location.Y=810|Color=8388608|FontID=1|IsHidden=T|Text=Altium Limited|Name=Publisher
|RECORD=41|OwnerIndex=862|IndexInSheet=8|OwnerPartId=-1|Location.X=930|Location.Y=810|Color=8388608|FontID=1|IsHidden=T|Text=Chip Resistor|Name=PackageDescription
|RECORD=41|OwnerIndex=862|IndexInSheet=9|OwnerPartId=-1|Location.X=900|Location.Y=790|Color=8388608|FontID=1|Text=0 Ohm|Name=Value
|RECORD=34|OwnerIndex=862|IndexInSheet=-1|OwnerPartId=-1|Location.X=929|Location.Y=804|Color=8388608|FontID=1|Text=R11|Name=Designator|ReadOnlyState=1
|RECORD=41|OwnerIndex=862|IndexInSheet=-1|OwnerPartId=-1|Location.X=929|Location.Y=786|Color=8388608|FontID=1|Text=MACTX|Name=Comment
|RECORD=44|OwnerIndex=862
|RECORD=45|OwnerIndex=877|IndexInSheet=-1|Description=Chip Resistor, Body 1.6x0.8mm, IPC High Density|UseComponentLibrary=T|ModelName=J1-0603|ModelType=PCBLIB|DatafileCount=1|ModelDatafileEntity0=J1-0603|ModelDatafileKind0=PCBLib|IsCurrent=T|DatalinksLocked=T|DatabaseDatalinksLocked=T|IntegratedModel=T|DatabaseModel=T
|RECORD=46|OwnerIndex=878
|RECORD=48|OwnerIndex=878
|RECORD=45|OwnerIndex=877|IndexInSheet=-1|Description=Chip Resistor, Body 3.2x2.5mm, IPC High Density|UseComponentLibrary=T|ModelName=14-1210|ModelType=PCBLIB|DatafileCount=1|ModelDatafileEntity0=14-1210|ModelDatafileKind0=PCBLib|DatalinksLocked=T|DatabaseDatalinksLocked=T|IntegratedModel=T|DatabaseModel=T
|RECORD=46|OwnerIndex=881
|RECORD=48|OwnerIndex=881
|RECORD=45|OwnerIndex=877|IndexInSheet=-1|Description=Chip Resistor, Body 5.0x2.5mm, IPC High Density|UseComponentLibrary=T|ModelName=12Z-2010|ModelType=PCBLIB|DatafileCount=1|ModelDatafileEntity0=12Z-2010|ModelDatafileKind0=PCBLib|DatalinksLocked=T|DatabaseDatalinksLocked=T|IntegratedModel=T|DatabaseModel=T
|RECORD=46|OwnerIndex=884
|RECORD=48|OwnerIndex=884
|RECORD=45|OwnerIndex=877|IndexInSheet=-1|Description=Chip Resistor, Body 6.3x3.2mm, IPC High Density|UseComponentLibrary=T|ModelName=RESC6332|ModelType=PCBLIB|DatafileCount=1|ModelDatafileEntity0=RESC6332|ModelDatafileKind0=PCBLib|DatalinksLocked=T|DatabaseDatalinksLocked=T|IntegratedModel=T|DatabaseModel=T
|RECORD=46|OwnerIndex=887
|RECORD=48|OwnerIndex=887
|RECORD=45|OwnerIndex=877|IndexInSheet=-1|Description=Resistor|UseComponentLibrary=T|ModelName=RESISTOR|ModelType=SIM|IsCurrent=T|DatalinksLocked=T|DatabaseDatalinksLocked=T|IntegratedModel=T|DatabaseModel=T
|RECORD=46|OwnerIndex=890
|RECORD=48|OwnerIndex=890
|RECORD=41|OwnerIndex=892|IndexInSheet=-1|OwnerPartId=-1|Color=8388608|FontID=1|Text=R|Name=Spice Prefix
|RECORD=41|OwnerIndex=892|IndexInSheet=-1|OwnerPartId=-1|Color=8388608|FontID=1|Text=@DESIGNATOR %1 %2 @VALUE|Name=Netlist
|RECORD=41|OwnerIndex=892|IndexInSheet=-1|OwnerPartId=-1|Color=8388608|FontID=1|Text=General|Name=Kind
|RECORD=41|OwnerIndex=892|IndexInSheet=-1|OwnerPartId=-1|Color=8388608|FontID=1|Text=Resistor|Name=SubKind
|RECORD=45|OwnerIndex=877|IndexInSheet=-1|UseComponentLibrary=T|ModelName=Res|ModelType=SI|IsCurrent=T|DatalinksLocked=T|DatabaseDatalinksLocked=T|IntegratedModel=T|DatabaseModel=T
|RECORD=46|OwnerIndex=897
|RECORD=48|OwnerIndex=897
|RECORD=41|OwnerIndex=899|IndexInSheet=-1|OwnerPartId=-1|Color=8388608|FontID=1|Text=Resistor|Name=Type
|RECORD=41|OwnerIndex=899|IndexInSheet=-1|OwnerPartId=-1|Color=8388608|FontID=1|Name=Tech
|RECORD=1|LibReference=Res3|ComponentDescription=Resistor|PartCount=2|DisplayModeCount=1|IndexInSheet=120|OwnerPartId=-1|Location.X=930|Location.Y=770|CurrentPartId=1|SourceLibraryName=Miscellaneous Devices.IntLib|TargetFileName=*|AreaColor=11599871|Color=128|PartIDLocked=F|DesignItemId=Res3|AllPinCount=2
|RECORD=2|OwnerIndex=902|OwnerPartId=1|FormalType=1|Electrical=4|PinConglomerate=34|PinLength=10|Location.X=930|Location.Y=760|Name=1|Designator=1|PinPropagationDelay=0.000000E+000
|RECORD=2|OwnerIndex=902|OwnerPartId=1|FormalType=1|Electrical=4|PinConglomerate=32|PinLength=10|Location.X=960|Location.Y=760|Name=2|Designator=2|PinPropagationDelay=0.000000E+000
|RECORD=6|OwnerIndex=902|IsNotAccesible=T|IndexInSheet=2|OwnerPartId=1|LineWidth=1|Color=16711680|LocationCount=7|X1=960|Y1=760|X2=957|Y2=763|X3=951|Y3=757|X4=945|Y4=763|X5=939|Y5=757|X6=933|Y6=763|X7=930|Y7=760
|RECORD=41|OwnerIndex=902|IndexInSheet=3|OwnerPartId=-1|Location.X=930|Location.Y=770|Color=8388608|FontID=1|IsHidden=T|Text=8-Jun-2000|Name=Published
|RECORD=41|OwnerIndex=902|IndexInSheet=4|OwnerPartId=-1|Location.X=930|Location.Y=770|Color=8388608|FontID=1|IsHidden=T|Text=29-May-2009|Name=LatestRevisionDate
|RECORD=41|OwnerIndex=902|IndexInSheet=5|OwnerPartId=-1|Location.X=930|Location.Y=770|Color=8388608|FontID=1|IsHidden=T|Text=IPC-7351 Footprint Added.|Name=LatestRevisionNote
|RECORD=41|OwnerIndex=902|IndexInSheet=6|OwnerPartId=-1|Location.X=930|Location.Y=770|Color=8388608|FontID=1|IsHidden=T|Text=J1-0603|Name=PackageReference
|RECORD=41|OwnerIndex=902|IndexInSheet=7|OwnerPartId=-1|Location.X=930|Location.Y=770|Color=8388608|FontID=1|IsHidden=T|Text=Altium Limited|Name=Publisher
|RECORD=41|OwnerIndex=902|IndexInSheet=8|OwnerPartId=-1|Location.X=930|Location.Y=770|Color=8388608|FontID=1|IsHidden=T|Text=Chip Resistor|Name=PackageDescription
|RECORD=41|OwnerIndex=902|IndexInSheet=9|OwnerPartId=-1|Location.X=900|Location.Y=750|Color=8388608|FontID=1|Text=0 Ohm|Name=Value
|RECORD=34|OwnerIndex=902|IndexInSheet=-1|OwnerPartId=-1|Location.X=929|Location.Y=764|Color=8388608|FontID=1|Text=R12|Name=Designator|ReadOnlyState=1
|RECORD=41|OwnerIndex=902|IndexInSheet=-1|OwnerPartId=-1|Location.X=929|Location.Y=746|Color=8388608|FontID=1|Text=GPS2RX|Name=Comment
|RECORD=44|OwnerIndex=902
|RECORD=45|OwnerIndex=917|IndexInSheet=-1|Description=Chip Resistor, Body 1.6x0.8mm, IPC High Density|UseComponentLibrary=T|ModelName=J1-0603|ModelType=PCBLIB|DatafileCount=1|ModelDatafileEntity0=J1-0603|ModelDatafileKind0=PCBLib|IsCurrent=T|DatalinksLocked=T|DatabaseDatalinksLocked=T|IntegratedModel=T|DatabaseModel=T
|RECORD=46|OwnerIndex=918
|RECORD=48|OwnerIndex=918
|RECORD=45|OwnerIndex=917|IndexInSheet=-1|Description=Chip Resistor, Body 3.2x2.5mm, IPC High Density|UseComponentLibrary=T|ModelName=14-1210|ModelType=PCBLIB|DatafileCount=1|ModelDatafileEntity0=14-1210|ModelDatafileKind0=PCBLib|DatalinksLocked=T|DatabaseDatalinksLocked=T|IntegratedModel=T|DatabaseModel=T
|RECORD=46|OwnerIndex=921
|RECORD=48|OwnerIndex=921
|RECORD=45|OwnerIndex=917|IndexInSheet=-1|Description=Chip Resistor, Body 5.0x2.5mm, IPC High Density|UseComponentLibrary=T|ModelName=12Z-2010|ModelType=PCBLIB|DatafileCount=1|ModelDatafileEntity0=12Z-2010|ModelDatafileKind0=PCBLib|DatalinksLocked=T|DatabaseDatalinksLocked=T|IntegratedModel=T|DatabaseModel=T
|RECORD=46|OwnerIndex=924
|RECORD=48|OwnerIndex=924
|RECORD=45|OwnerIndex=917|IndexInSheet=-1|Description=Chip Resistor, Body 6.3x3.2mm, IPC High Density|UseComponentLibrary=T|ModelName=RESC6332|ModelType=PCBLIB|DatafileCount=1|ModelDatafileEntity0=RESC6332|ModelDatafileKind0=PCBLib|DatalinksLocked=T|DatabaseDatalinksLocked=T|IntegratedModel=T|DatabaseModel=T
|RECORD=46|OwnerIndex=927
|RECORD=48|OwnerIndex=927
|RECORD=45|OwnerIndex=917|IndexInSheet=-1|Description=Resistor|UseComponentLibrary=T|ModelName=RESISTOR|ModelType=SIM|IsCurrent=T|DatalinksLocked=T|DatabaseDatalinksLocked=T|IntegratedModel=T|DatabaseModel=T
|RECORD=46|OwnerIndex=930
|RECORD=48|OwnerIndex=930
|RECORD=41|OwnerIndex=932|IndexInSheet=-1|OwnerPartId=-1|Color=8388608|FontID=1|Text=R|Name=Spice Prefix
|RECORD=41|OwnerIndex=932|IndexInSheet=-1|OwnerPartId=-1|Color=8388608|FontID=1|Text=@DESIGNATOR %1 %2 @VALUE|Name=Netlist
|RECORD=41|OwnerIndex=932|IndexInSheet=-1|OwnerPartId=-1|Color=8388608|FontID=1|Text=General|Name=Kind
|RECORD=41|OwnerIndex=932|IndexInSheet=-1|OwnerPartId=-1|Color=8388608|FontID=1|Text=Resistor|Name=SubKind
|RECORD=45|OwnerIndex=917|IndexInSheet=-1|UseComponentLibrary=T|ModelName=Res|ModelType=SI|IsCurrent=T|DatalinksLocked=T|DatabaseDatalinksLocked=T|IntegratedModel=T|DatabaseModel=T
|RECORD=46|OwnerIndex=937
|RECORD=48|OwnerIndex=937
|RECORD=41|OwnerIndex=939|IndexInSheet=-1|OwnerPartId=-1|Color=8388608|FontID=1|Text=Resistor|Name=Type
|RECORD=41|OwnerIndex=939|IndexInSheet=-1|OwnerPartId=-1|Color=8388608|FontID=1|Name=Tech
|RECORD=1|LibReference=Res3|ComponentDescription=Resistor|PartCount=2|DisplayModeCount=1|IndexInSheet=121|OwnerPartId=-1|Location.X=930|Location.Y=740|CurrentPartId=1|SourceLibraryName=Miscellaneous Devices.IntLib|TargetFileName=*|AreaColor=11599871|Color=128|PartIDLocked=F|DesignItemId=Res3|AllPinCount=2
|RECORD=2|OwnerIndex=942|OwnerPartId=1|FormalType=1|Electrical=4|PinConglomerate=34|PinLength=10|Location.X=930|Location.Y=730|Name=1|Designator=1|PinPropagationDelay=0.000000E+000
|RECORD=2|OwnerIndex=942|OwnerPartId=1|FormalType=1|Electrical=4|PinConglomerate=32|PinLength=10|Location.X=960|Location.Y=730|Name=2|Designator=2|PinPropagationDelay=0.000000E+000
|RECORD=6|OwnerIndex=942|IsNotAccesible=T|IndexInSheet=2|OwnerPartId=1|LineWidth=1|Color=16711680|LocationCount=7|X1=960|Y1=730|X2=957|Y2=733|X3=951|Y3=727|X4=945|Y4=733|X5=939|Y5=727|X6=933|Y6=733|X7=930|Y7=730
|RECORD=41|OwnerIndex=942|IndexInSheet=3|OwnerPartId=-1|Location.X=930|Location.Y=740|Color=8388608|FontID=1|IsHidden=T|Text=8-Jun-2000|Name=Published
|RECORD=41|OwnerIndex=942|IndexInSheet=4|OwnerPartId=-1|Location.X=930|Location.Y=740|Color=8388608|FontID=1|IsHidden=T|Text=29-May-2009|Name=LatestRevisionDate
|RECORD=41|OwnerIndex=942|IndexInSheet=5|OwnerPartId=-1|Location.X=930|Location.Y=740|Color=8388608|FontID=1|IsHidden=T|Text=IPC-7351 Footprint Added.|Name=LatestRevisionNote
|RECORD=41|OwnerIndex=942|IndexInSheet=6|OwnerPartId=-1|Location.X=930|Location.Y=740|Color=8388608|FontID=1|IsHidden=T|Text=J1-0603|Name=PackageReference
|RECORD=41|OwnerIndex=942|IndexInSheet=7|OwnerPartId=-1|Location.X=930|Location.Y=740|Color=8388608|FontID=1|IsHidden=T|Text=Altium Limited|Name=Publisher
|RECORD=41|OwnerIndex=942|IndexInSheet=8|OwnerPartId=-1|Location.X=930|Location.Y=740|Color=8388608|FontID=1|IsHidden=T|Text=Chip Resistor|Name=PackageDescription
|RECORD=41|OwnerIndex=942|IndexInSheet=9|OwnerPartId=-1|Location.X=900|Location.Y=720|Color=8388608|FontID=1|Text=0 Ohm|Name=Value
|RECORD=34|OwnerIndex=942|IndexInSheet=-1|OwnerPartId=-1|Location.X=929|Location.Y=734|Color=8388608|FontID=1|Text=R13|Name=Designator|ReadOnlyState=1
|RECORD=41|OwnerIndex=942|IndexInSheet=-1|OwnerPartId=-1|Location.X=929|Location.Y=716|Color=8388608|FontID=1|Text=MACRX|Name=Comment
|RECORD=44|OwnerIndex=942
|RECORD=45|OwnerIndex=957|IndexInSheet=-1|Description=Chip Resistor, Body 1.6x0.8mm, IPC High Density|UseComponentLibrary=T|ModelName=J1-0603|ModelType=PCBLIB|DatafileCount=1|ModelDatafileEntity0=J1-0603|ModelDatafileKind0=PCBLib|IsCurrent=T|DatalinksLocked=T|DatabaseDatalinksLocked=T|IntegratedModel=T|DatabaseModel=T
|RECORD=46|OwnerIndex=958
|RECORD=48|OwnerIndex=958
|RECORD=45|OwnerIndex=957|IndexInSheet=-1|Description=Chip Resistor, Body 3.2x2.5mm, IPC High Density|UseComponentLibrary=T|ModelName=14-1210|ModelType=PCBLIB|DatafileCount=1|ModelDatafileEntity0=14-1210|ModelDatafileKind0=PCBLib|DatalinksLocked=T|DatabaseDatalinksLocked=T|IntegratedModel=T|DatabaseModel=T
|RECORD=46|OwnerIndex=961
|RECORD=48|OwnerIndex=961
|RECORD=45|OwnerIndex=957|IndexInSheet=-1|Description=Chip Resistor, Body 5.0x2.5mm, IPC High Density|UseComponentLibrary=T|ModelName=12Z-2010|ModelType=PCBLIB|DatafileCount=1|ModelDatafileEntity0=12Z-2010|ModelDatafileKind0=PCBLib|DatalinksLocked=T|DatabaseDatalinksLocked=T|IntegratedModel=T|DatabaseModel=T
|RECORD=46|OwnerIndex=964
|RECORD=48|OwnerIndex=964
|RECORD=45|OwnerIndex=957|IndexInSheet=-1|Description=Chip Resistor, Body 6.3x3.2mm, IPC High Density|UseComponentLibrary=T|ModelName=RESC6332|ModelType=PCBLIB|DatafileCount=1|ModelDatafileEntity0=RESC6332|ModelDatafileKind0=PCBLib|DatalinksLocked=T|DatabaseDatalinksLocked=T|IntegratedModel=T|DatabaseModel=T
|RECORD=46|OwnerIndex=967
|RECORD=48|OwnerIndex=967
|RECORD=45|OwnerIndex=957|IndexInSheet=-1|Description=Resistor|UseComponentLibrary=T|ModelName=RESISTOR|ModelType=SIM|IsCurrent=T|DatalinksLocked=T|DatabaseDatalinksLocked=T|IntegratedModel=T|DatabaseModel=T
|RECORD=46|OwnerIndex=970
|RECORD=48|OwnerIndex=970
|RECORD=41|OwnerIndex=972|IndexInSheet=-1|OwnerPartId=-1|Color=8388608|FontID=1|Text=R|Name=Spice Prefix
|RECORD=41|OwnerIndex=972|IndexInSheet=-1|OwnerPartId=-1|Color=8388608|FontID=1|Text=@DESIGNATOR %1 %2 @VALUE|Name=Netlist
|RECORD=41|OwnerIndex=972|IndexInSheet=-1|OwnerPartId=-1|Color=8388608|FontID=1|Text=General|Name=Kind
|RECORD=41|OwnerIndex=972|IndexInSheet=-1|OwnerPartId=-1|Color=8388608|FontID=1|Text=Resistor|Name=SubKind
|RECORD=45|OwnerIndex=957|IndexInSheet=-1|UseComponentLibrary=T|ModelName=Res|ModelType=SI|IsCurrent=T|DatalinksLocked=T|DatabaseDatalinksLocked=T|IntegratedModel=T|DatabaseModel=T
|RECORD=46|OwnerIndex=977
|RECORD=48|OwnerIndex=977
|RECORD=41|OwnerIndex=979|IndexInSheet=-1|OwnerPartId=-1|Color=8388608|FontID=1|Text=Resistor|Name=Type
|RECORD=41|OwnerIndex=979|IndexInSheet=-1|OwnerPartId=-1|Color=8388608|FontID=1|Name=Tech
|RECORD=1|LibReference=BMP388|ComponentDescription=Integrated Circuit|PartCount=2|DisplayModeCount=1|IndexInSheet=122|OwnerPartId=-1|Location.X=1180|Location.Y=510|CurrentPartId=1|LibraryPath=*|SourceLibraryName=*|SheetPartFileName=*|TargetFileName=*|AreaColor=11599871|Color=128|PartIDLocked=F|PinsMoveable=T|DesignItemId=BMP388|AllPinCount=10
|RECORD=14|OwnerIndex=982|IsNotAccesible=T|OwnerPartId=1|Location.X=1200|Location.Y=450|Corner.X=1280|Corner.Y=560|LineWidth=1|Color=128|AreaColor=11599871|IsSolid=T
|RECORD=2|OwnerIndex=982|OwnerPartId=1|FormalType=1|Electrical=4|PinConglomerate=24|PinLength=20|Location.X=1280|Location.Y=540|Name=VDDIO|Designator=1|SwapIDPart=Ž&Ž||PinPropagationDelay=0.000000E+000
|RECORD=2|OwnerIndex=982|OwnerPartId=1|FormalType=1|Electrical=4|PinConglomerate=26|PinLength=20|Location.X=1200|Location.Y=550|Name=SCK|Designator=2|SwapIDPart=Ž&Ž||PinPropagationDelay=0.000000E+000
|RECORD=2|OwnerIndex=982|OwnerPartId=1|FormalType=1|Electrical=4|PinConglomerate=24|PinLength=20|Location.X=1280|Location.Y=480|Name=VSS_1|Designator=3|SwapIDPart=Ž&Ž||PinPropagationDelay=0.000000E+000
|RECORD=2|OwnerIndex=982|OwnerPartId=1|FormalType=1|Electrical=4|PinConglomerate=26|PinLength=20|Location.X=1200|Location.Y=540|Name=SDI|Designator=4|SwapIDPart=Ž&Ž||PinPropagationDelay=0.000000E+000
|RECORD=2|OwnerIndex=982|OwnerPartId=1|FormalType=1|Electrical=4|PinConglomerate=26|PinLength=20|Location.X=1200|Location.Y=520|Name=SDO|Designator=5|SwapIDPart=Ž&Ž||PinPropagationDelay=0.000000E+000
|RECORD=2|OwnerIndex=982|OwnerPartId=1|FormalType=1|Electrical=4|PinConglomerate=24|PinLength=20|Location.X=1280|Location.Y=510|Name=CSB|Designator=6|SwapIDPart=Ž&Ž||PinPropagationDelay=0.000000E+000
|RECORD=2|OwnerIndex=982|OwnerPartId=1|FormalType=1|Electrical=4|PinConglomerate=26|PinLength=20|Location.X=1200|Location.Y=470|Name=INT|Designator=7|SwapIDPart=Ž&Ž||PinPropagationDelay=0.000000E+000
|RECORD=2|OwnerIndex=982|OwnerPartId=1|FormalType=1|Electrical=4|PinConglomerate=24|PinLength=20|Location.X=1280|Location.Y=460|Name=VSS_2|Designator=8|SwapIDPart=Ž&Ž||PinPropagationDelay=0.000000E+000
|RECORD=2|OwnerIndex=982|OwnerPartId=1|FormalType=1|Electrical=4|PinConglomerate=24|PinLength=20|Location.X=1280|Location.Y=470|Name=VSS_3|Designator=9|SwapIDPart=Ž&Ž||PinPropagationDelay=0.000000E+000
|RECORD=2|OwnerIndex=982|OwnerPartId=1|FormalType=1|Electrical=4|PinConglomerate=24|PinLength=20|Location.X=1280|Location.Y=550|Name=VDD|Designator=10|SwapIDPart=Ž&Ž||PinPropagationDelay=0.000000E+000
|RECORD=41|OwnerIndex=982|IndexInSheet=11|OwnerPartId=-1|Location.X=1178|Location.Y=582|Color=8388608|FontID=5|IsHidden=T|Text=https://ae-bst.resource.bosch.com/media/_tech/media/datasheets/BST-BMP388-DS001-01.pdf|Name=Datasheet Link
|RECORD=41|OwnerIndex=982|IndexInSheet=12|OwnerPartId=-1|Location.X=1178|Location.Y=582|Color=8388608|FontID=1|IsHidden=T|Text=0mm|Name=Height
|RECORD=41|OwnerIndex=982|IndexInSheet=13|OwnerPartId=-1|Location.X=1178|Location.Y=582|Color=8388608|FontID=1|IsHidden=T|Text=Bosch Sensortec|Name=Manufacturer_Name
|RECORD=41|OwnerIndex=982|IndexInSheet=14|OwnerPartId=-1|Location.X=1178|Location.Y=582|Color=8388608|FontID=1|IsHidden=T|Text=BMP388|Name=Manufacturer_Part_Number
|RECORD=41|OwnerIndex=982|IndexInSheet=15|OwnerPartId=-1|Location.X=1178|Location.Y=582|Color=8388608|FontID=1|IsHidden=T|Text=BMP388|Name=Arrow Part Number
|RECORD=41|OwnerIndex=982|IndexInSheet=16|OwnerPartId=-1|Location.X=1178|Location.Y=582|Color=8388608|FontID=5|IsHidden=T|Text=https://www.arrow.com/en/products/bmp388/bosch|Name=Arrow Price/Stock
|RECORD=41|OwnerIndex=982|IndexInSheet=17|OwnerPartId=-1|Location.X=1178|Location.Y=582|Color=8388608|FontID=1|IsHidden=T|Text=262-BMP388|Name=Mouser Part Number
|RECORD=41|OwnerIndex=982|IndexInSheet=18|OwnerPartId=-1|Location.X=1178|Location.Y=582|Color=8388608|FontID=5|IsHidden=T|Text=https://www.mouser.co.uk/ProductDetail/Bosch-Sensortec/BMP388?qs=rrS6PyfT74eIcD5Rv1Kf7A%3D%3D|Name=Mouser Price/Stock
|RECORD=34|OwnerIndex=982|IndexInSheet=-1|OwnerPartId=-1|Location.X=1200|Location.Y=570|Color=8388608|FontID=1|Text=U4|Name=Designator|ReadOnlyState=1
|RECORD=41|OwnerIndex=982|IndexInSheet=-1|OwnerPartId=-1|Location.X=1200|Location.Y=560|Color=8388608|FontID=1|Text=BMP388|Name=Comment
|RECORD=44|OwnerIndex=982
|RECORD=45|OwnerIndex=1014|IndexInSheet=-1|ModelName=BMP388|ModelType=PCBLIB|DatafileCount=1|ModelDatafile0=C:\Users\<user>\Documents\AltiumLL\SamacSys.PcbLib|ModelDatafileEntity0=BMP388|ModelDatafileKind0=PCBLIB|IsCurrent=T
|RECORD=46|OwnerIndex=1015
|RECORD=48|OwnerIndex=1015
|RECORD=17|IndexInSheet=123|OwnerPartId=-1|Style=4|ShowNetName=T|Location.X=1320|Location.Y=420|Orientation=3|Color=128|FontID=1|Text=GND
|RECORD=17|IndexInSheet=124|OwnerPartId=-1|ShowNetName=T|Location.X=1120|Location.Y=540|Orientation=2|Color=255|FontID=1|Text=SDA|IsCrossSheetConnector=T
|RECORD=17|IndexInSheet=125|OwnerPartId=-1|ShowNetName=T|Location.X=1120|Location.Y=550|Orientation=2|Color=255|FontID=1|Text=SCL|IsCrossSheetConnector=T
|RECORD=22|IndexInSheet=126|OwnerPartId=-1|Location.X=1180|Location.Y=520|Color=255|Orientation=1|Symbol=Thin Cross|IsActive=T|SuppressAll=T
|RECORD=22|IndexInSheet=127|OwnerPartId=-1|Location.X=1180|Location.Y=470|Color=255|Symbol=Thin Cross|IsActive=T|SuppressAll=T
|RECORD=4|IndexInSheet=128|OwnerPartId=-1|Location.X=1150|Location.Y=620|Color=8388608|FontID=4|Text=PRESSURE SENSOR
|RECORD=1|LibReference=93fe34f5f049140596bab6421a6454b|ComponentDescription=IC EEPROM 2K I2C 1MHZ SOT23-5|PartCount=2|DisplayModeCount=1|IndexInSheet=129|OwnerPartId=-1|Location.X=1180|Location.Y=250|CurrentPartId=1|LibraryPath=*|SourceLibraryName=Altium Content Vault|TargetFileName=*|AreaColor=11599871|Color=128|PartIDLocked=T|DesignItemId=CMP-06313-000011-1|AllPinCount=5
|RECORD=14|OwnerIndex=1024|IsNotAccesible=T|OwnerPartId=1|Location.X=1200|Location.Y=200|Corner.X=1270|Corner.Y=260|LineWidth=1|Color=128|AreaColor=11599871|IsSolid=T
|RECORD=2|OwnerIndex=1024|OwnerPartId=1|Electrical=7|PinConglomerate=58|PinLength=20|Location.X=1200|Location.Y=250|Name=VCC|Designator=4|PinPropagationDelay=0.000000E+000
|RECORD=2|OwnerIndex=1024|OwnerPartId=1|SymBol_InnerEdge=3|PinConglomerate=56|PinLength=20|Location.X=1270|Location.Y=250|Name=SCL|Designator=1|PinPropagationDelay=0.000000E+000
|RECORD=2|OwnerIndex=1024|OwnerPartId=1|Electrical=1|PinConglomerate=56|PinLength=20|Location.X=1270|Location.Y=240|Name=SDA|Designator=3|PinPropagationDelay=0.000000E+000
|RECORD=2|OwnerIndex=1024|OwnerPartId=1|PinConglomerate=58|PinLength=20|Location.X=1200|Location.Y=210|Name=WP|Designator=5|PinPropagationDelay=0.000000E+000
|RECORD=2|OwnerIndex=1024|OwnerPartId=1|Electrical=7|PinConglomerate=56|PinLength=20|Location.X=1270|Location.Y=210|Name=GND|Designator=2|PinPropagationDelay=0.000000E+000
|RECORD=41|OwnerIndex=1024|IndexInSheet=6|OwnerPartId=-1|Location.X=1178|Location.Y=260|Color=8388608|FontID=1|IsHidden=T|Text=-40°C|Name=Temperature Range Low
|RECORD=41|OwnerIndex=1024|IndexInSheet=7|OwnerPartId=-1|Location.X=1178|Location.Y=260|Color=8388608|FontID=1|IsHidden=T|Text=1mm|Name=Height
|RECORD=41|OwnerIndex=1024|IndexInSheet=8|OwnerPartId=-1|Location.X=1178|Location.Y=260|Color=8388608|FontID=5|IsHidden=T|Text=http://ww1.microchip.com/downloads/en/DeviceDoc/Atmel-8807-SEEPROM-AT24MAC402-602-Datasheet.pdf|Name=ComponentLink2URL
|RECORD=41|OwnerIndex=1024|IndexInSheet=9|OwnerPartId=-1|Location.X=1178|Location.Y=260|Color=8388608|FontID=1|IsHidden=T|Text=SOT95P280X100-5|Name=Ipc Land Pattern Name
|RECORD=41|OwnerIndex=1024|IndexInSheet=10|OwnerPartId=-1|Location.X=1178|Location.Y=260|Color=8388608|FontID=1|IsHidden=T|Text=2Kbits|Name=Memory Size
|RECORD=41|OwnerIndex=1024|IndexInSheet=11|OwnerPartId=-1|Location.X=1178|Location.Y=260|Color=8388608|FontID=1|IsHidden=T|Text=IC|Name=Category
|RECORD=41|OwnerIndex=1024|IndexInSheet=12|OwnerPartId=-1|Location.X=1178|Location.Y=260|Color=8388608|FontID=1|IsHidden=T|Text=EEPROM|Name=Memory Type
|RECORD=41|OwnerIndex=1024|IndexInSheet=13|OwnerPartId=-1|Location.X=1178|Location.Y=260|Color=8388608|FontID=1|IsHidden=T|Text=IC EEPROM 2K I2C 1MHZ SOT23-5|Name=Digikey Description
|RECORD=41|OwnerIndex=1024|IndexInSheet=14|OwnerPartId=-1|Location.X=1178|Location.Y=260|Color=8388608|FontID=1|IsHidden=T|Text=1.7V|Name=Min Supply Voltage
|RECORD=41|OwnerIndex=1024|IndexInSheet=15|OwnerPartId=-1|Location.X=1178|Location.Y=260|Color=8388608|FontID=1|IsHidden=T|Text=AT24MAC402-STUM-T|Name=Manufacturer Part Number
|RECORD=41|OwnerIndex=1024|IndexInSheet=16|OwnerPartId=-1|Location.X=1178|Location.Y=260|Color=8388608|FontID=1|IsHidden=T|Text=Integrated Circuits (ICs)|Name=Device Class L1
|RECORD=41|OwnerIndex=1024|IndexInSheet=17|OwnerPartId=-1|Location.X=1178|Location.Y=260|Color=8388608|FontID=1|IsHidden=T|Text=+85°C|Name=Temperature Range High
|RECORD=41|OwnerIndex=1024|IndexInSheet=18|OwnerPartId=-1|Location.X=1178|Location.Y=260|Color=8388608|FontID=1|IsHidden=T|Text=Datasheet|Name=ComponentLink2Description
|RECORD=41|OwnerIndex=1024|IndexInSheet=19|OwnerPartId=-1|Location.X=1178|Location.Y=260|Color=8388608|FontID=1|IsHidden=T|Text=5.5V|Name=Max Supply Voltage
|RECORD=41|OwnerIndex=1024|IndexInSheet=20|OwnerPartId=-1|Location.X=1178|Location.Y=260|Color=8388608|FontID=1|IsHidden=T|Text=TRUE|Name=RoHS
|RECORD=41|OwnerIndex=1024|IndexInSheet=21|OwnerPartId=-1|Location.X=1178|Location.Y=260|Color=8388608|FontID=1|IsHidden=T|Text=1000kHz|Name=Frequency
|RECORD=41|OwnerIndex=1024|IndexInSheet=22|OwnerPartId=-1|Location.X=1178|Location.Y=260|Color=8388608|FontID=1|IsHidden=T|Text=EEPROM Serial-I2C 2K-bit 256 x 8 1.8V/2.5V/3.3V/5V 5-Pin SOT-23 T/R|Name=Mouser Description
|RECORD=41|OwnerIndex=1024|IndexInSheet=23|OwnerPartId=-1|Location.X=1178|Location.Y=260|Color=8388608|FontID=1|IsHidden=T|Text=Microchip|Name=Manufacturer
|RECORD=41|OwnerIndex=1024|IndexInSheet=24|OwnerPartId=-1|Location.X=1178|Location.Y=260|Color=8388608|FontID=1|IsHidden=T|Text=0mm|Name=Standoff Height
|RECORD=41|OwnerIndex=1024|IndexInSheet=25|OwnerPartId=-1|Location.X=1178|Location.Y=260|Color=8388608|FontID=5|IsHidden=T|Text=https://octopart.com/at24mac402-stum-t-microchip-77758112|Name=Octopart
|RECORD=41|OwnerIndex=1024|IndexInSheet=26|OwnerPartId=-1|Location.X=1178|Location.Y=260|Color=8388608|FontID=1|IsHidden=T|Text=0.4-2mA|Name=Nominal Supply Current
|RECORD=41|OwnerIndex=1024|IndexInSheet=27|OwnerPartId=-1|Location.X=1178|Location.Y=260|Color=8388608|FontID=1|IsHidden=T|Text=-40°C to +85°C|Name=Temperature
|RECORD=41|OwnerIndex=1024|IndexInSheet=28|OwnerPartId=-1|Location.X=1178|Location.Y=260|Color=8388608|FontID=1|IsHidden=T|Text=5TS1|Name=Package
|RECORD=41|OwnerIndex=1024|IndexInSheet=29|OwnerPartId=-1|Location.X=1178|Location.Y=260|Color=8388608|FontID=1|IsHidden=T|Text=EEPROM|Name=Device Class L3
|RECORD=41|OwnerIndex=1024|IndexInSheet=30|OwnerPartId=-1|Location.X=1178|Location.Y=260|Color=8388608|FontID=1|IsHidden=T|Text=No|Name=Automotive
|RECORD=41|OwnerIndex=1024|IndexInSheet=31|OwnerPartId=-1|Location.X=1178|Location.Y=260|Color=8388608|FontID=1|IsHidden=T|Text=0.55us|Name=Access Time
|RECORD=41|OwnerIndex=1024|IndexInSheet=32|OwnerPartId=-1|Location.X=1178|Location.Y=260|Color=8388608|FontID=1|IsHidden=T|Text=Memory|Name=Device Class L2
|RECORD=41|OwnerIndex=1024|IndexInSheet=33|OwnerPartId=-1|Location.X=1178|Location.Y=260|Color=8388608|FontID=1|IsHidden=T|Text=Yes|Name=Lead Free
|RECORD=41|OwnerIndex=1024|IndexInSheet=34|OwnerPartId=-1|Location.X=1178|Location.Y=260|Color=8388608|FontID=1|IsHidden=T|Text=I2C,2-Wire|Name=Interface
|RECORD=34|OwnerIndex=1024|IndexInSheet=-1|OwnerPartId=-1|Location.X=1200|Location.Y=260|Color=8388608|FontID=1|Text=U7|Name=Designator|ReadOnlyState=1
|RECORD=41|OwnerIndex=1024|IndexInSheet=-1|OwnerPartId=1|Location.X=1200|Location.Y=190|Color=8388608|FontID=1|Text=AT24MAC402-STUM-T|Name=Comment
|RECORD=44|OwnerIndex=1024
|RECORD=45|OwnerIndex=1067|IndexInSheet=-1|UseComponentLibrary=T|ModelName=FP-5TS1-IPC_C|ModelType=PCBLIB|DatafileCount=1|ModelDatafileEntity0=FP-5TS1-IPC_C|ModelDatafileKind0=PCBLib|IsCurrent=T|DatalinksLocked=T|DatabaseDatalinksLocked=T
|RECORD=46|OwnerIndex=1068
|RECORD=48|OwnerIndex=1068
|RECORD=45|OwnerIndex=1067|IndexInSheet=-1|UseComponentLibrary=T|ModelName=FP-5TS1-IPC_B|ModelType=PCBLIB|DatafileCount=1|ModelDatafileEntity0=FP-5TS1-IPC_B|ModelDatafileKind0=PCBLib|DatalinksLocked=T|DatabaseDatalinksLocked=T
|RECORD=46|OwnerIndex=1071
|RECORD=48|OwnerIndex=1071
|RECORD=45|OwnerIndex=1067|IndexInSheet=-1|UseComponentLibrary=T|ModelName=FP-5TS1-IPC_A|ModelType=PCBLIB|DatafileCount=1|ModelDatafileEntity0=FP-5TS1-IPC_A|ModelDatafileKind0=PCBLib|DatalinksLocked=T|DatabaseDatalinksLocked=T
|RECORD=46|OwnerIndex=1074
|RECORD=48|OwnerIndex=1074
|RECORD=17|IndexInSheet=130|OwnerPartId=-1|ShowNetName=T|Location.X=1370|Location.Y=240|Color=255|FontID=1|Text=SDA|IsCrossSheetConnector=T
|RECORD=17|IndexInSheet=131|OwnerPartId=-1|ShowNetName=T|Location.X=1370|Location.Y=250|Color=255|FontID=1|Text=SCL|IsCrossSheetConnector=T
|RECORD=17|IndexInSheet=132|OwnerPartId=-1|ShowNetName=T|Location.X=1140|Location.Y=300|Orientation=1|Color=128|FontID=1|Text=+3.3V
|RECORD=17|IndexInSheet=133|OwnerPartId=-1|Style=4|ShowNetName=T|Location.X=1330|Location.Y=150|Orientation=3|Color=128|FontID=1|Text=GND
|RECORD=1|LibReference=CAP|ComponentDescription=C0603X104K5RACAUTO|PartCount=2|DisplayModeCount=2|IndexInSheet=134|OwnerPartId=-1|Location.X=210|Location.Y=890|Orientation=1|CurrentPartId=1|SourceLibraryName=Altium Content Vault|TargetFileName=*|AreaColor=11599871|Color=128|PartIDLocked=F|DesignItemId=CMP-2006-00003-1|AllPinCount=2
|RECORD=2|OwnerIndex=1081|OwnerPartId=1|OwnerPartDisplayMode=1|FormalType=1|Electrical=4|PinConglomerate=35|PinLength=10|Location.X=220|Location.Y=890|Name=1|Designator=1|PinPropagationDelay=0.000000E+000
|RECORD=2|OwnerIndex=1081|OwnerPartId=1|OwnerPartDisplayMode=1|FormalType=1|Electrical=4|PinConglomerate=33|PinLength=10|Location.X=220|Location.Y=900|Name=2|Designator=2|PinPropagationDelay=0.000000E+000
|RECORD=13|OwnerIndex=1081|IsNotAccesible=T|IndexInSheet=2|OwnerPartId=1|OwnerPartDisplayMode=1|Location.X=228|Location.Y=890|Corner.X=212|Corner.Y=890|LineWidth=1|Color=16711680
|RECORD=13|OwnerIndex=1081|IsNotAccesible=T|IndexInSheet=3|OwnerPartId=1|OwnerPartDisplayMode=1|Location.X=220|Location.Y=894|Corner.X=220|Corner.Y=900|LineWidth=1|Color=16711680
|RECORD=12|OwnerIndex=1081|IsNotAccesible=T|IndexInSheet=4|OwnerPartId=1|OwnerPartDisplayMode=1|Location.X=220|Location.Y=910|Radius=16|LineWidth=1|StartAngle=241.000|EndAngle=270.000|Color=16711680
|RECORD=12|OwnerIndex=1081|IsNotAccesible=T|IndexInSheet=5|OwnerPartId=1|OwnerPartDisplayMode=1|Location.X=220|Location.Y=910|Radius=16|LineWidth=1|StartAngle=270.000|EndAngle=299.000|Color=16711680
|RECORD=2|OwnerIndex=1081|OwnerPartId=1|FormalType=1|Electrical=4|PinConglomerate=35|PinLength=10|Location.X=220|Location.Y=890|Name=1|Designator=1|PinPropagationDelay=0.000000E+000
|RECORD=2|OwnerIndex=1081|OwnerPartId=1|FormalType=1|Electrical=4|PinConglomerate=33|PinLength=10|Location.X=220|Location.Y=900|Name=2|Designator=2|PinPropagationDelay=0.000000E+000
|RECORD=13|OwnerIndex=1081|IsNotAccesible=T|IndexInSheet=8|OwnerPartId=1|Location.X=212|Location.Y=897|Corner.X=228|Corner.Y=897|LineWidth=1|Color=16711680
|RECORD=13|OwnerIndex=1081|IsNotAccesible=T|IndexInSheet=9|OwnerPartId=1|Location.X=228|Location.Y=893|Corner.X=212|Corner.Y=893|LineWidth=1|Color=16711680
|RECORD=6|OwnerIndex=1081|IsNotAccesible=T|IndexInSheet=10|OwnerPartId=1|LineWidth=1|Color=16711680|LocationCount=2|X1=220|Y1=890|X2=220|Y2=893
|RECORD=6|OwnerIndex=1081|IsNotAccesible=T|IndexInSheet=11|OwnerPartId=1|LineWidth=1|Color=16711680|LocationCount=2|X1=220|Y1=900|X2=220|Y2=897
|RECORD=41|OwnerIndex=1081|IndexInSheet=12|OwnerPartId=-1|Location.X=211|Location.Y=912|Color=8388608|FontID=1|IsHidden=T|Text=Kemet|Name=Manufacturer
|RECORD=41|OwnerIndex=1081|IndexInSheet=13|OwnerPartId=-1|Location.X=211|Location.Y=912|Color=8388608|FontID=1|IsHidden=T|Text=C0603X104K5RACAUTO|Name=Part Number
|RECORD=34|OwnerIndex=1081|IndexInSheet=-1|OwnerPartId=-1|Location.X=229|Location.Y=891|Color=8388608|FontID=3|Text=C59|Name=Designator|ReadOnlyState=1
|RECORD=41|OwnerIndex=1081|IndexInSheet=-1|OwnerPartId=-1|Location.X=229|Location.Y=881|Color=8388608|FontID=3|Text=0.1uF|Name=Comment
|RECORD=44|OwnerIndex=1081
|RECORD=45|OwnerIndex=1102|IndexInSheet=-1|Description=Chip Capacitor, 2-Leads, Body 1.60x0.80mm, IPC Low Density|UseComponentLibrary=T|ModelName=CAPC1608X87X45ML20T05|ModelType=PCBLIB|DatafileCount=1|ModelDatafileEntity0=CAPC1608X87X45ML20T05|ModelDatafileKind0=PCBLib|IsCurrent=T|DatalinksLocked=T|DatabaseDatalinksLocked=T
|RECORD=46|OwnerIndex=1103
|RECORD=48|OwnerIndex=1103
|RECORD=41|OwnerIndex=1105|IndexInSheet=-1|OwnerPartId=-1|Color=8388608|FontID=1|Text=2D|Name=Available Preview Images
|RECORD=45|OwnerIndex=1102|IndexInSheet=-1|Description=Chip Capacitor, 2-Leads, Body 1.60x0.80mm, IPC High Density|UseComponentLibrary=T|ModelName=CAPC1608X87X45LL20T05|ModelType=PCBLIB|DatafileCount=1|ModelDatafileEntity0=CAPC1608X87X45LL20T05|ModelDatafileKind0=PCBLib|DatalinksLocked=T|DatabaseDatalinksLocked=T
|RECORD=46|OwnerIndex=1107
|RECORD=48|OwnerIndex=1107
|RECORD=41|OwnerIndex=1109|IndexInSheet=-1|OwnerPartId=-1|Color=8388608|FontID=1|Text=2D|Name=Available Preview Images
|RECORD=45|OwnerIndex=1102|IndexInSheet=-1|Description=Chip Capacitor, 2-Leads, Body 1.60x0.80mm, IPC Medium Density|UseComponentLibrary=T|ModelName=CAPC1608X87X45NL20T05|ModelType=PCBLIB|DatafileCount=1|ModelDatafileEntity0=CAPC1608X87X45NL20T05|ModelDatafileKind0=PCBLib|DatalinksLocked=T|DatabaseDatalinksLocked=T
|RECORD=46|OwnerIndex=1111
|RECORD=48|OwnerIndex=1111
|RECORD=41|OwnerIndex=1113|IndexInSheet=-1|OwnerPartId=-1|Color=8388608|FontID=1|Text=2D|Name=Available Preview Images
|RECORD=1|LibReference=CAP|ComponentDescription=C0603X104K5RACAUTO|PartCount=2|DisplayModeCount=2|IndexInSheet=135|OwnerPartId=-1|Location.X=310|Location.Y=890|Orientation=1|CurrentPartId=1|SourceLibraryName=Altium Content Vault|TargetFileName=*|AreaColor=11599871|Color=128|PartIDLocked=F|DesignItemId=CMP-2006-00003-1|AllPinCount=2
|RECORD=2|OwnerIndex=1115|OwnerPartId=1|OwnerPartDisplayMode=1|FormalType=1|Electrical=4|PinConglomerate=35|PinLength=10|Location.X=320|Location.Y=890|Name=1|Designator=1|PinPropagationDelay=0.000000E+000
|RECORD=2|OwnerIndex=1115|OwnerPartId=1|OwnerPartDisplayMode=1|FormalType=1|Electrical=4|PinConglomerate=33|PinLength=10|Location.X=320|Location.Y=900|Name=2|Designator=2|PinPropagationDelay=0.000000E+000
|RECORD=13|OwnerIndex=1115|IsNotAccesible=T|IndexInSheet=2|OwnerPartId=1|OwnerPartDisplayMode=1|Location.X=328|Location.Y=890|Corner.X=312|Corner.Y=890|LineWidth=1|Color=16711680
|RECORD=13|OwnerIndex=1115|IsNotAccesible=T|IndexInSheet=3|OwnerPartId=1|OwnerPartDisplayMode=1|Location.X=320|Location.Y=894|Corner.X=320|Corner.Y=900|LineWidth=1|Color=16711680
|RECORD=12|OwnerIndex=1115|IsNotAccesible=T|IndexInSheet=4|OwnerPartId=1|OwnerPartDisplayMode=1|Location.X=320|Location.Y=910|Radius=16|LineWidth=1|StartAngle=241.000|EndAngle=270.000|Color=16711680
|RECORD=12|OwnerIndex=1115|IsNotAccesible=T|IndexInSheet=5|OwnerPartId=1|OwnerPartDisplayMode=1|Location.X=320|Location.Y=910|Radius=16|LineWidth=1|StartAngle=270.000|EndAngle=299.000|Color=16711680
|RECORD=2|OwnerIndex=1115|OwnerPartId=1|FormalType=1|Electrical=4|PinConglomerate=35|PinLength=10|Location.X=320|Location.Y=890|Name=1|Designator=1|PinPropagationDelay=0.000000E+000
|RECORD=2|OwnerIndex=1115|OwnerPartId=1|FormalType=1|Electrical=4|PinConglomerate=33|PinLength=10|Location.X=320|Location.Y=900|Name=2|Designator=2|PinPropagationDelay=0.000000E+000
|RECORD=13|OwnerIndex=1115|IsNotAccesible=T|IndexInSheet=8|OwnerPartId=1|Location.X=312|Location.Y=897|Corner.X=328|Corner.Y=897|LineWidth=1|Color=16711680
|RECORD=13|OwnerIndex=1115|IsNotAccesible=T|IndexInSheet=9|OwnerPartId=1|Location.X=328|Location.Y=893|Corner.X=312|Corner.Y=893|LineWidth=1|Color=16711680
|RECORD=6|OwnerIndex=1115|IsNotAccesible=T|IndexInSheet=10|OwnerPartId=1|LineWidth=1|Color=16711680|LocationCount=2|X1=320|Y1=890|X2=320|Y2=893
|RECORD=6|OwnerIndex=1115|IsNotAccesible=T|IndexInSheet=11|OwnerPartId=1|LineWidth=1|Color=16711680|LocationCount=2|X1=320|Y1=900|X2=320|Y2=897
|RECORD=41|OwnerIndex=1115|IndexInSheet=12|OwnerPartId=-1|Location.X=311|Location.Y=912|Color=8388608|FontID=1|IsHidden=T|Text=Kemet|Name=Manufacturer
|RECORD=41|OwnerIndex=1115|IndexInSheet=13|OwnerPartId=-1|Location.X=311|Location.Y=912|Color=8388608|FontID=1|IsHidden=T|Text=C0603X104K5RACAUTO|Name=Part Number
|RECORD=34|OwnerIndex=1115|IndexInSheet=-1|OwnerPartId=-1|Location.X=329|Location.Y=891|Color=8388608|FontID=3|Text=C61|Name=Designator|ReadOnlyState=1
|RECORD=41|OwnerIndex=1115|IndexInSheet=-1|OwnerPartId=-1|Location.X=329|Location.Y=881|Color=8388608|FontID=3|Text=0.1uF|Name=Comment
|RECORD=44|OwnerIndex=1115
|RECORD=45|OwnerIndex=1136|IndexInSheet=-1|Description=Chip Capacitor, 2-Leads, Body 1.60x0.80mm, IPC Low Density|UseComponentLibrary=T|ModelName=CAPC1608X87X45ML20T05|ModelType=PCBLIB|DatafileCount=1|ModelDatafileEntity0=CAPC1608X87X45ML20T05|ModelDatafileKind0=PCBLib|IsCurrent=T|DatalinksLocked=T|DatabaseDatalinksLocked=T
|RECORD=46|OwnerIndex=1137
|RECORD=48|OwnerIndex=1137
|RECORD=41|OwnerIndex=1139|IndexInSheet=-1|OwnerPartId=-1|Color=8388608|FontID=1|Text=2D|Name=Available Preview Images
|RECORD=45|OwnerIndex=1136|IndexInSheet=-1|Description=Chip Capacitor, 2-Leads, Body 1.60x0.80mm, IPC High Density|UseComponentLibrary=T|ModelName=CAPC1608X87X45LL20T05|ModelType=PCBLIB|DatafileCount=1|ModelDatafileEntity0=CAPC1608X87X45LL20T05|ModelDatafileKind0=PCBLib|DatalinksLocked=T|DatabaseDatalinksLocked=T
|RECORD=46|OwnerIndex=1141
|RECORD=48|OwnerIndex=1141
|RECORD=41|OwnerIndex=1143|IndexInSheet=-1|OwnerPartId=-1|Color=8388608|FontID=1|Text=2D|Name=Available Preview Images
|RECORD=45|OwnerIndex=1136|IndexInSheet=-1|Description=Chip Capacitor, 2-Leads, Body 1.60x0.80mm, IPC Medium Density|UseComponentLibrary=T|ModelName=CAPC1608X87X45NL20T05|ModelType=PCBLIB|DatafileCount=1|ModelDatafileEntity0=CAPC1608X87X45NL20T05|ModelDatafileKind0=PCBLib|DatalinksLocked=T|DatabaseDatalinksLocked=T
|RECORD=46|OwnerIndex=1145
|RECORD=48|OwnerIndex=1145
|RECORD=41|OwnerIndex=1147|IndexInSheet=-1|OwnerPartId=-1|Color=8388608|FontID=1|Text=2D|Name=Available Preview Images
|RECORD=1|LibReference=CAP|ComponentDescription=C0603X104K5RACAUTO|PartCount=2|DisplayModeCount=2|IndexInSheet=136|OwnerPartId=-1|Location.X=210|Location.Y=710|Orientation=1|CurrentPartId=1|SourceLibraryName=Altium Content Vault|TargetFileName=*|AreaColor=11599871|Color=128|PartIDLocked=F|DesignItemId=CMP-2006-00003-1|AllPinCount=2
|RECORD=2|OwnerIndex=1149|OwnerPartId=1|OwnerPartDisplayMode=1|FormalType=1|Electrical=4|PinConglomerate=35|PinLength=10|Location.X=220|Location.Y=710|Name=1|Designator=1|PinPropagationDelay=0.000000E+000
|RECORD=2|OwnerIndex=1149|OwnerPartId=1|OwnerPartDisplayMode=1|FormalType=1|Electrical=4|PinConglomerate=33|PinLength=10|Location.X=220|Location.Y=720|Name=2|Designator=2|PinPropagationDelay=0.000000E+000
|RECORD=13|OwnerIndex=1149|IsNotAccesible=T|IndexInSheet=2|OwnerPartId=1|OwnerPartDisplayMode=1|Location.X=228|Location.Y=710|Corner.X=212|Corner.Y=710|LineWidth=1|Color=16711680
|RECORD=13|OwnerIndex=1149|IsNotAccesible=T|IndexInSheet=3|OwnerPartId=1|OwnerPartDisplayMode=1|Location.X=220|Location.Y=714|Corner.X=220|Corner.Y=720|LineWidth=1|Color=16711680
|RECORD=12|OwnerIndex=1149|IsNotAccesible=T|IndexInSheet=4|OwnerPartId=1|OwnerPartDisplayMode=1|Location.X=220|Location.Y=730|Radius=16|LineWidth=1|StartAngle=241.000|EndAngle=270.000|Color=16711680
|RECORD=12|OwnerIndex=1149|IsNotAccesible=T|IndexInSheet=5|OwnerPartId=1|OwnerPartDisplayMode=1|Location.X=220|Location.Y=730|Radius=16|LineWidth=1|StartAngle=270.000|EndAngle=299.000|Color=16711680
|RECORD=2|OwnerIndex=1149|OwnerPartId=1|FormalType=1|Electrical=4|PinConglomerate=35|PinLength=10|Location.X=220|Location.Y=710|Name=1|Designator=1|PinPropagationDelay=0.000000E+000
|RECORD=2|OwnerIndex=1149|OwnerPartId=1|FormalType=1|Electrical=4|PinConglomerate=33|PinLength=10|Location.X=220|Location.Y=720|Name=2|Designator=2|PinPropagationDelay=0.000000E+000
|RECORD=13|OwnerIndex=1149|IsNotAccesible=T|IndexInSheet=8|OwnerPartId=1|Location.X=212|Location.Y=717|Corner.X=228|Corner.Y=717|LineWidth=1|Color=16711680
|RECORD=13|OwnerIndex=1149|IsNotAccesible=T|IndexInSheet=9|OwnerPartId=1|Location.X=228|Location.Y=713|Corner.X=212|Corner.Y=713|LineWidth=1|Color=16711680
|RECORD=6|OwnerIndex=1149|IsNotAccesible=T|IndexInSheet=10|OwnerPartId=1|LineWidth=1|Color=16711680|LocationCount=2|X1=220|Y1=710|X2=220|Y2=713
|RECORD=6|OwnerIndex=1149|IsNotAccesible=T|IndexInSheet=11|OwnerPartId=1|LineWidth=1|Color=16711680|LocationCount=2|X1=220|Y1=720|X2=220|Y2=717
|RECORD=41|OwnerIndex=1149|IndexInSheet=12|OwnerPartId=-1|Location.X=211|Location.Y=732|Color=8388608|FontID=1|IsHidden=T|Text=Kemet|Name=Manufacturer
|RECORD=41|OwnerIndex=1149|IndexInSheet=13|OwnerPartId=-1|Location.X=211|Location.Y=732|Color=8388608|FontID=1|IsHidden=T|Text=C0603X104K5RACAUTO|Name=Part Number
|RECORD=34|OwnerIndex=1149|IndexInSheet=-1|OwnerPartId=-1|Location.X=229|Location.Y=711|Color=8388608|FontID=3|Text=C88|Name=Designator|ReadOnlyState=1
|RECORD=41|OwnerIndex=1149|IndexInSheet=-1|OwnerPartId=-1|Location.X=229|Location.Y=701|Color=8388608|FontID=3|Text=0.1uF|Name=Comment
|RECORD=44|OwnerIndex=1149
|RECORD=45|OwnerIndex=1170|IndexInSheet=-1|Description=Chip Capacitor, 2-Leads, Body 1.60x0.80mm, IPC Low Density|UseComponentLibrary=T|ModelName=CAPC1608X87X45ML20T05|ModelType=PCBLIB|DatafileCount=1|ModelDatafileEntity0=CAPC1608X87X45ML20T05|ModelDatafileKind0=PCBLib|IsCurrent=T|DatalinksLocked=T|DatabaseDatalinksLocked=T
|RECORD=46|OwnerIndex=1171
|RECORD=48|OwnerIndex=1171
|RECORD=41|OwnerIndex=1173|IndexInSheet=-1|OwnerPartId=-1|Color=8388608|FontID=1|Text=2D|Name=Available Preview Images
|RECORD=45|OwnerIndex=1170|IndexInSheet=-1|Description=Chip Capacitor, 2-Leads, Body 1.60x0.80mm, IPC High Density|UseComponentLibrary=T|ModelName=CAPC1608X87X45LL20T05|ModelType=PCBLIB|DatafileCount=1|ModelDatafileEntity0=CAPC1608X87X45LL20T05|ModelDatafileKind0=PCBLib|DatalinksLocked=T|DatabaseDatalinksLocked=T
|RECORD=46|OwnerIndex=1175
|RECORD=48|OwnerIndex=1175
|RECORD=41|OwnerIndex=1177|IndexInSheet=-1|OwnerPartId=-1|Color=8388608|FontID=1|Text=2D|Name=Available Preview Images
|RECORD=45|OwnerIndex=1170|IndexInSheet=-1|Description=Chip Capacitor, 2-Leads, Body 1.60x0.80mm, IPC Medium Density|UseComponentLibrary=T|ModelName=CAPC1608X87X45NL20T05|ModelType=PCBLIB|DatafileCount=1|ModelDatafileEntity0=CAPC1608X87X45NL20T05|ModelDatafileKind0=PCBLib|DatalinksLocked=T|DatabaseDatalinksLocked=T
|RECORD=46|OwnerIndex=1179
|RECORD=48|OwnerIndex=1179
|RECORD=41|OwnerIndex=1181|IndexInSheet=-1|OwnerPartId=-1|Color=8388608|FontID=1|Text=2D|Name=Available Preview Images
|RECORD=1|LibReference=CAP|ComponentDescription=C0603X104K5RACAUTO|PartCount=2|DisplayModeCount=2|IndexInSheet=137|OwnerPartId=-1|Location.X=310|Location.Y=710|Orientation=1|CurrentPartId=1|SourceLibraryName=Altium Content Vault|TargetFileName=*|AreaColor=11599871|Color=128|PartIDLocked=F|DesignItemId=CMP-2006-00003-1|AllPinCount=2
|RECORD=2|OwnerIndex=1183|OwnerPartId=1|OwnerPartDisplayMode=1|FormalType=1|Electrical=4|PinConglomerate=35|PinLength=10|Location.X=320|Location.Y=710|Name=1|Designator=1|PinPropagationDelay=0.000000E+000
|RECORD=2|OwnerIndex=1183|OwnerPartId=1|OwnerPartDisplayMode=1|FormalType=1|Electrical=4|PinConglomerate=33|PinLength=10|Location.X=320|Location.Y=720|Name=2|Designator=2|PinPropagationDelay=0.000000E+000
|RECORD=13|OwnerIndex=1183|IsNotAccesible=T|IndexInSheet=2|OwnerPartId=1|OwnerPartDisplayMode=1|Location.X=328|Location.Y=710|Corner.X=312|Corner.Y=710|LineWidth=1|Color=16711680
|RECORD=13|OwnerIndex=1183|IsNotAccesible=T|IndexInSheet=3|OwnerPartId=1|OwnerPartDisplayMode=1|Location.X=320|Location.Y=714|Corner.X=320|Corner.Y=720|LineWidth=1|Color=16711680
|RECORD=12|OwnerIndex=1183|IsNotAccesible=T|IndexInSheet=4|OwnerPartId=1|OwnerPartDisplayMode=1|Location.X=320|Location.Y=730|Radius=16|LineWidth=1|StartAngle=241.000|EndAngle=270.000|Color=16711680
|RECORD=12|OwnerIndex=1183|IsNotAccesible=T|IndexInSheet=5|OwnerPartId=1|OwnerPartDisplayMode=1|Location.X=320|Location.Y=730|Radius=16|LineWidth=1|StartAngle=270.000|EndAngle=299.000|Color=16711680
|RECORD=2|OwnerIndex=1183|OwnerPartId=1|FormalType=1|Electrical=4|PinConglomerate=35|PinLength=10|Location.X=320|Location.Y=710|Name=1|Designator=1|PinPropagationDelay=0.000000E+000
|RECORD=2|OwnerIndex=1183|OwnerPartId=1|FormalType=1|Electrical=4|PinConglomerate=33|PinLength=10|Location.X=320|Location.Y=720|Name=2|Designator=2|PinPropagationDelay=0.000000E+000
|RECORD=13|OwnerIndex=1183|IsNotAccesible=T|IndexInSheet=8|OwnerPartId=1|Location.X=312|Location.Y=717|Corner.X=328|Corner.Y=717|LineWidth=1|Color=16711680
|RECORD=13|OwnerIndex=1183|IsNotAccesible=T|IndexInSheet=9|OwnerPartId=1|Location.X=328|Location.Y=713|Corner.X=312|Corner.Y=713|LineWidth=1|Color=16711680
|RECORD=6|OwnerIndex=1183|IsNotAccesible=T|IndexInSheet=10|OwnerPartId=1|LineWidth=1|Color=16711680|LocationCount=2|X1=320|Y1=710|X2=320|Y2=713
|RECORD=6|OwnerIndex=1183|IsNotAccesible=T|IndexInSheet=11|OwnerPartId=1|LineWidth=1|Color=16711680|LocationCount=2|X1=320|Y1=720|X2=320|Y2=717
|RECORD=41|OwnerIndex=1183|IndexInSheet=12|OwnerPartId=-1|Location.X=311|Location.Y=732|Color=8388608|FontID=1|IsHidden=T|Text=Kemet|Name=Manufacturer
|RECORD=41|OwnerIndex=1183|IndexInSheet=13|OwnerPartId=-1|Location.X=311|Location.Y=732|Color=8388608|FontID=1|IsHidden=T|Text=C0603X104K5RACAUTO|Name=Part Number
|RECORD=34|OwnerIndex=1183|IndexInSheet=-1|OwnerPartId=-1|Location.X=329|Location.Y=711|Color=8388608|FontID=3|Text=C90|Name=Designator|ReadOnlyState=1
|RECORD=41|OwnerIndex=1183|IndexInSheet=-1|OwnerPartId=-1|Location.X=329|Location.Y=701|Color=8388608|FontID=3|Text=0.1uF|Name=Comment
|RECORD=44|OwnerIndex=1183
|RECORD=45|OwnerIndex=1204|IndexInSheet=-1|Description=Chip Capacitor, 2-Leads, Body 1.60x0.80mm, IPC Low Density|UseComponentLibrary=T|ModelName=CAPC1608X87X45ML20T05|ModelType=PCBLIB|DatafileCount=1|ModelDatafileEntity0=CAPC1608X87X45ML20T05|ModelDatafileKind0=PCBLib|IsCurrent=T|DatalinksLocked=T|DatabaseDatalinksLocked=T
|RECORD=46|OwnerIndex=1205
|RECORD=48|OwnerIndex=1205
|RECORD=41|OwnerIndex=1207|IndexInSheet=-1|OwnerPartId=-1|Color=8388608|FontID=1|Text=2D|Name=Available Preview Images
|RECORD=45|OwnerIndex=1204|IndexInSheet=-1|Description=Chip Capacitor, 2-Leads, Body 1.60x0.80mm, IPC High Density|UseComponentLibrary=T|ModelName=CAPC1608X87X45LL20T05|ModelType=PCBLIB|DatafileCount=1|ModelDatafileEntity0=CAPC1608X87X45LL20T05|ModelDatafileKind0=PCBLib|DatalinksLocked=T|DatabaseDatalinksLocked=T
|RECORD=46|OwnerIndex=1209
|RECORD=48|OwnerIndex=1209
|RECORD=41|OwnerIndex=1211|IndexInSheet=-1|OwnerPartId=-1|Color=8388608|FontID=1|Text=2D|Name=Available Preview Images
|RECORD=45|OwnerIndex=1204|IndexInSheet=-1|Description=Chip Capacitor, 2-Leads, Body 1.60x0.80mm, IPC Medium Density|UseComponentLibrary=T|ModelName=CAPC1608X87X45NL20T05|ModelType=PCBLIB|DatafileCount=1|ModelDatafileEntity0=CAPC1608X87X45NL20T05|ModelDatafileKind0=PCBLib|DatalinksLocked=T|DatabaseDatalinksLocked=T
|RECORD=46|OwnerIndex=1213
|RECORD=48|OwnerIndex=1213
|RECORD=41|OwnerIndex=1215|IndexInSheet=-1|OwnerPartId=-1|Color=8388608|FontID=1|Text=2D|Name=Available Preview Images
|RECORD=1|LibReference=CAP|ComponentDescription=C0603X104K5RACAUTO|PartCount=2|DisplayModeCount=2|IndexInSheet=138|OwnerPartId=-1|Location.X=240|Location.Y=310|Orientation=1|CurrentPartId=1|SourceLibraryName=Altium Content Vault|TargetFileName=*|AreaColor=11599871|Color=128|PartIDLocked=F|DesignItemId=CMP-2006-00003-1|AllPinCount=2
|RECORD=2|OwnerIndex=1217|OwnerPartId=1|OwnerPartDisplayMode=1|FormalType=1|Electrical=4|PinConglomerate=35|PinLength=10|Location.X=250|Location.Y=310|Name=1|Designator=1|PinPropagationDelay=0.000000E+000
|RECORD=2|OwnerIndex=1217|OwnerPartId=1|OwnerPartDisplayMode=1|FormalType=1|Electrical=4|PinConglomerate=33|PinLength=10|Location.X=250|Location.Y=320|Name=2|Designator=2|PinPropagationDelay=0.000000E+000
|RECORD=13|OwnerIndex=1217|IsNotAccesible=T|IndexInSheet=2|OwnerPartId=1|OwnerPartDisplayMode=1|Location.X=258|Location.Y=310|Corner.X=242|Corner.Y=310|LineWidth=1|Color=16711680
|RECORD=13|OwnerIndex=1217|IsNotAccesible=T|IndexInSheet=3|OwnerPartId=1|OwnerPartDisplayMode=1|Location.X=250|Location.Y=314|Corner.X=250|Corner.Y=320|LineWidth=1|Color=16711680
|RECORD=12|OwnerIndex=1217|IsNotAccesible=T|IndexInSheet=4|OwnerPartId=1|OwnerPartDisplayMode=1|Location.X=250|Location.Y=330|Radius=16|LineWidth=1|StartAngle=241.000|EndAngle=270.000|Color=16711680
|RECORD=12|OwnerIndex=1217|IsNotAccesible=T|IndexInSheet=5|OwnerPartId=1|OwnerPartDisplayMode=1|Location.X=250|Location.Y=330|Radius=16|LineWidth=1|StartAngle=270.000|EndAngle=299.000|Color=16711680
|RECORD=2|OwnerIndex=1217|OwnerPartId=1|FormalType=1|Electrical=4|PinConglomerate=35|PinLength=10|Location.X=250|Location.Y=310|Name=1|Designator=1|PinPropagationDelay=0.000000E+000
|RECORD=2|OwnerIndex=1217|OwnerPartId=1|FormalType=1|Electrical=4|PinConglomerate=33|PinLength=10|Location.X=250|Location.Y=320|Name=2|Designator=2|PinPropagationDelay=0.000000E+000
|RECORD=13|OwnerIndex=1217|IsNotAccesible=T|IndexInSheet=8|OwnerPartId=1|Location.X=242|Location.Y=317|Corner.X=258|Corner.Y=317|LineWidth=1|Color=16711680
|RECORD=13|OwnerIndex=1217|IsNotAccesible=T|IndexInSheet=9|OwnerPartId=1|Location.X=258|Location.Y=313|Corner.X=242|Corner.Y=313|LineWidth=1|Color=16711680
|RECORD=6|OwnerIndex=1217|IsNotAccesible=T|IndexInSheet=10|OwnerPartId=1|LineWidth=1|Color=16711680|LocationCount=2|X1=250|Y1=310|X2=250|Y2=313
|RECORD=6|OwnerIndex=1217|IsNotAccesible=T|IndexInSheet=11|OwnerPartId=1|LineWidth=1|Color=16711680|LocationCount=2|X1=250|Y1=320|X2=250|Y2=317
|RECORD=41|OwnerIndex=1217|IndexInSheet=12|OwnerPartId=-1|Location.X=241|Location.Y=332|Color=8388608|FontID=1|IsHidden=T|Text=Kemet|Name=Manufacturer
|RECORD=41|OwnerIndex=1217|IndexInSheet=13|OwnerPartId=-1|Location.X=241|Location.Y=332|Color=8388608|FontID=1|IsHidden=T|Text=C0603X104K5RACAUTO|Name=Part Number
|RECORD=34|OwnerIndex=1217|IndexInSheet=-1|OwnerPartId=-1|Location.X=259|Location.Y=311|Color=8388608|FontID=3|Text=C57|Name=Designator|ReadOnlyState=1
|RECORD=41|OwnerIndex=1217|IndexInSheet=-1|OwnerPartId=-1|Location.X=259|Location.Y=301|Color=8388608|FontID=3|Text=0.1uF|Name=Comment
|RECORD=44|OwnerIndex=1217
|RECORD=45|OwnerIndex=1238|IndexInSheet=-1|Description=Chip Capacitor, 2-Leads, Body 1.60x0.80mm, IPC Low Density|UseComponentLibrary=T|ModelName=CAPC1608X87X45ML20T05|ModelType=PCBLIB|DatafileCount=1|ModelDatafileEntity0=CAPC1608X87X45ML20T05|ModelDatafileKind0=PCBLib|IsCurrent=T|DatalinksLocked=T|DatabaseDatalinksLocked=T
|RECORD=46|OwnerIndex=1239
|RECORD=48|OwnerIndex=1239
|RECORD=41|OwnerIndex=1241|IndexInSheet=-1|OwnerPartId=-1|Color=8388608|FontID=1|Text=2D|Name=Available Preview Images
|RECORD=45|OwnerIndex=1238|IndexInSheet=-1|Description=Chip Capacitor, 2-Leads, Body 1.60x0.80mm, IPC High Density|UseComponentLibrary=T|ModelName=CAPC1608X87X45LL20T05|ModelType=PCBLIB|DatafileCount=1|ModelDatafileEntity0=CAPC1608X87X45LL20T05|ModelDatafileKind0=PCBLib|DatalinksLocked=T|DatabaseDatalinksLocked=T
|RECORD=46|OwnerIndex=1243
|RECORD=48|OwnerIndex=1243
|RECORD=41|OwnerIndex=1245|IndexInSheet=-1|OwnerPartId=-1|Color=8388608|FontID=1|Text=2D|Name=Available Preview Images
|RECORD=45|OwnerIndex=1238|IndexInSheet=-1|Description=Chip Capacitor, 2-Leads, Body 1.60x0.80mm, IPC Medium Density|UseComponentLibrary=T|ModelName=CAPC1608X87X45NL20T05|ModelType=PCBLIB|DatafileCount=1|ModelDatafileEntity0=CAPC1608X87X45NL20T05|ModelDatafileKind0=PCBLib|DatalinksLocked=T|DatabaseDatalinksLocked=T
|RECORD=46|OwnerIndex=1247
|RECORD=48|OwnerIndex=1247
|RECORD=41|OwnerIndex=1249|IndexInSheet=-1|OwnerPartId=-1|Color=8388608|FontID=1|Text=2D|Name=Available Preview Images
|RECORD=1|LibReference=CAP|ComponentDescription=C0603X104K5RACAUTO|PartCount=2|DisplayModeCount=2|IndexInSheet=139|OwnerPartId=-1|Location.X=1130|Location.Y=170|Orientation=1|CurrentPartId=1|SourceLibraryName=Altium Content Vault|TargetFileName=*|AreaColor=11599871|Color=128|PartIDLocked=F|DesignItemId=CMP-2006-00003-1|AllPinCount=2
|RECORD=2|OwnerIndex=1251|OwnerPartId=1|OwnerPartDisplayMode=1|FormalType=1|Electrical=4|PinConglomerate=35|PinLength=10|Location.X=1140|Location.Y=170|Name=1|Designator=1|PinPropagationDelay=0.000000E+000
|RECORD=2|OwnerIndex=1251|OwnerPartId=1|OwnerPartDisplayMode=1|FormalType=1|Electrical=4|PinConglomerate=33|PinLength=10|Location.X=1140|Location.Y=180|Name=2|Designator=2|PinPropagationDelay=0.000000E+000
|RECORD=13|OwnerIndex=1251|IsNotAccesible=T|IndexInSheet=2|OwnerPartId=1|OwnerPartDisplayMode=1|Location.X=1148|Location.Y=170|Corner.X=1132|Corner.Y=170|LineWidth=1|Color=16711680
|RECORD=13|OwnerIndex=1251|IsNotAccesible=T|IndexInSheet=3|OwnerPartId=1|OwnerPartDisplayMode=1|Location.X=1140|Location.Y=174|Corner.X=1140|Corner.Y=180|LineWidth=1|Color=16711680
|RECORD=12|OwnerIndex=1251|IsNotAccesible=T|IndexInSheet=4|OwnerPartId=1|OwnerPartDisplayMode=1|Location.X=1140|Location.Y=190|Radius=16|LineWidth=1|StartAngle=241.000|EndAngle=270.000|Color=16711680
|RECORD=12|OwnerIndex=1251|IsNotAccesible=T|IndexInSheet=5|OwnerPartId=1|OwnerPartDisplayMode=1|Location.X=1140|Location.Y=190|Radius=16|LineWidth=1|StartAngle=270.000|EndAngle=299.000|Color=16711680
|RECORD=2|OwnerIndex=1251|OwnerPartId=1|FormalType=1|Electrical=4|PinConglomerate=35|PinLength=10|Location.X=1140|Location.Y=170|Name=1|Designator=1|PinPropagationDelay=0.000000E+000
|RECORD=2|OwnerIndex=1251|OwnerPartId=1|FormalType=1|Electrical=4|PinConglomerate=33|PinLength=10|Location.X=1140|Location.Y=180|Name=2|Designator=2|PinPropagationDelay=0.000000E+000
|RECORD=13|OwnerIndex=1251|IsNotAccesible=T|IndexInSheet=8|OwnerPartId=1|Location.X=1132|Location.Y=177|Corner.X=1148|Corner.Y=177|LineWidth=1|Color=16711680
|RECORD=13|OwnerIndex=1251|IsNotAccesible=T|IndexInSheet=9|OwnerPartId=1|Location.X=1148|Location.Y=173|Corner.X=1132|Corner.Y=173|LineWidth=1|Color=16711680
|RECORD=6|OwnerIndex=1251|IsNotAccesible=T|IndexInSheet=10|OwnerPartId=1|LineWidth=1|Color=16711680|LocationCount=2|X1=1140|Y1=170|X2=1140|Y2=173
|RECORD=6|OwnerIndex=1251|IsNotAccesible=T|IndexInSheet=11|OwnerPartId=1|LineWidth=1|Color=16711680|LocationCount=2|X1=1140|Y1=180|X2=1140|Y2=177
|RECORD=41|OwnerIndex=1251|IndexInSheet=12|OwnerPartId=-1|Location.X=1131|Location.Y=192|Color=8388608|FontID=1|IsHidden=T|Text=Kemet|Name=Manufacturer
|RECORD=41|OwnerIndex=1251|IndexInSheet=13|OwnerPartId=-1|Location.X=1131|Location.Y=192|Color=8388608|FontID=1|IsHidden=T|Text=C0603X104K5RACAUTO|Name=Part Number
|RECORD=34|OwnerIndex=1251|IndexInSheet=-1|OwnerPartId=-1|Location.X=1149|Location.Y=171|Color=8388608|FontID=3|Text=C25|Name=Designator|ReadOnlyState=1
|RECORD=41|OwnerIndex=1251|IndexInSheet=-1|OwnerPartId=-1|Location.X=1149|Location.Y=161|Color=8388608|FontID=3|Text=0.1uF|Name=Comment
|RECORD=44|OwnerIndex=1251
|RECORD=45|OwnerIndex=1272|IndexInSheet=-1|Description=Chip Capacitor, 2-Leads, Body 1.60x0.80mm, IPC Low Density|UseComponentLibrary=T|ModelName=CAPC1608X87X45ML20T05|ModelType=PCBLIB|DatafileCount=1|ModelDatafileEntity0=CAPC1608X87X45ML20T05|ModelDatafileKind0=PCBLib|IsCurrent=T|DatalinksLocked=T|DatabaseDatalinksLocked=T
|RECORD=46|OwnerIndex=1273
|RECORD=48|OwnerIndex=1273
|RECORD=41|OwnerIndex=1275|IndexInSheet=-1|OwnerPartId=-1|Color=8388608|FontID=1|Text=2D|Name=Available Preview Images
|RECORD=45|OwnerIndex=1272|IndexInSheet=-1|Description=Chip Capacitor, 2-Leads, Body 1.60x0.80mm, IPC High Density|UseComponentLibrary=T|ModelName=CAPC1608X87X45LL20T05|ModelType=PCBLIB|DatafileCount=1|ModelDatafileEntity0=CAPC1608X87X45LL20T05|ModelDatafileKind0=PCBLib|DatalinksLocked=T|DatabaseDatalinksLocked=T
|RECORD=46|OwnerIndex=1277
|RECORD=48|OwnerIndex=1277
|RECORD=41|OwnerIndex=1279|IndexInSheet=-1|OwnerPartId=-1|Color=8388608|FontID=1|Text=2D|Name=Available Preview Images
|RECORD=45|OwnerIndex=1272|IndexInSheet=-1|Description=Chip Capacitor, 2-Leads, Body 1.60x0.80mm, IPC Medium Density|UseComponentLibrary=T|ModelName=CAPC1608X87X45NL20T05|ModelType=PCBLIB|DatafileCount=1|ModelDatafileEntity0=CAPC1608X87X45NL20T05|ModelDatafileKind0=PCBLib|DatalinksLocked=T|DatabaseDatalinksLocked=T
|RECORD=46|OwnerIndex=1281
|RECORD=48|OwnerIndex=1281
|RECORD=41|OwnerIndex=1283|IndexInSheet=-1|OwnerPartId=-1|Color=8388608|FontID=1|Text=2D|Name=Available Preview Images
|RECORD=1|LibReference=CAP|ComponentDescription=C0603X104K5RACAUTO|PartCount=2|DisplayModeCount=2|IndexInSheet=140|OwnerPartId=-1|Location.X=1340|Location.Y=450|Orientation=1|CurrentPartId=1|SourceLibraryName=Altium Content Vault|TargetFileName=*|AreaColor=11599871|Color=128|PartIDLocked=F|DesignItemId=CMP-2006-00003-1|AllPinCount=2
|RECORD=2|OwnerIndex=1285|OwnerPartId=1|OwnerPartDisplayMode=1|FormalType=1|Electrical=4|PinConglomerate=35|PinLength=10|Location.X=1350|Location.Y=450|Name=1|Designator=1|PinPropagationDelay=0.000000E+000
|RECORD=2|OwnerIndex=1285|OwnerPartId=1|OwnerPartDisplayMode=1|FormalType=1|Electrical=4|PinConglomerate=33|PinLength=10|Location.X=1350|Location.Y=460|Name=2|Designator=2|PinPropagationDelay=0.000000E+000
|RECORD=13|OwnerIndex=1285|IsNotAccesible=T|IndexInSheet=2|OwnerPartId=1|OwnerPartDisplayMode=1|Location.X=1358|Location.Y=450|Corner.X=1342|Corner.Y=450|LineWidth=1|Color=16711680
|RECORD=13|OwnerIndex=1285|IsNotAccesible=T|IndexInSheet=3|OwnerPartId=1|OwnerPartDisplayMode=1|Location.X=1350|Location.Y=454|Corner.X=1350|Corner.Y=460|LineWidth=1|Color=16711680
|RECORD=12|OwnerIndex=1285|IsNotAccesible=T|IndexInSheet=4|OwnerPartId=1|OwnerPartDisplayMode=1|Location.X=1350|Location.Y=470|Radius=16|LineWidth=1|StartAngle=241.000|EndAngle=270.000|Color=16711680
|RECORD=12|OwnerIndex=1285|IsNotAccesible=T|IndexInSheet=5|OwnerPartId=1|OwnerPartDisplayMode=1|Location.X=1350|Location.Y=470|Radius=16|LineWidth=1|StartAngle=270.000|EndAngle=299.000|Color=16711680
|RECORD=2|OwnerIndex=1285|OwnerPartId=1|FormalType=1|Electrical=4|PinConglomerate=35|PinLength=10|Location.X=1350|Location.Y=450|Name=1|Designator=1|PinPropagationDelay=0.000000E+000
|RECORD=2|OwnerIndex=1285|OwnerPartId=1|FormalType=1|Electrical=4|PinConglomerate=33|PinLength=10|Location.X=1350|Location.Y=460|Name=2|Designator=2|PinPropagationDelay=0.000000E+000
|RECORD=13|OwnerIndex=1285|IsNotAccesible=T|IndexInSheet=8|OwnerPartId=1|Location.X=1342|Location.Y=457|Corner.X=1358|Corner.Y=457|LineWidth=1|Color=16711680
|RECORD=13|OwnerIndex=1285|IsNotAccesible=T|IndexInSheet=9|OwnerPartId=1|Location.X=1358|Location.Y=453|Corner.X=1342|Corner.Y=453|LineWidth=1|Color=16711680
|RECORD=6|OwnerIndex=1285|IsNotAccesible=T|IndexInSheet=10|OwnerPartId=1|LineWidth=1|Color=16711680|LocationCount=2|X1=1350|Y1=450|X2=1350|Y2=453
|RECORD=6|OwnerIndex=1285|IsNotAccesible=T|IndexInSheet=11|OwnerPartId=1|LineWidth=1|Color=16711680|LocationCount=2|X1=1350|Y1=460|X2=1350|Y2=457
|RECORD=41|OwnerIndex=1285|IndexInSheet=12|OwnerPartId=-1|Location.X=1341|Location.Y=472|Color=8388608|FontID=1|IsHidden=T|Text=Kemet|Name=Manufacturer
|RECORD=41|OwnerIndex=1285|IndexInSheet=13|OwnerPartId=-1|Location.X=1341|Location.Y=472|Color=8388608|FontID=1|IsHidden=T|Text=C0603X104K5RACAUTO|Name=Part Number
|RECORD=34|OwnerIndex=1285|IndexInSheet=-1|OwnerPartId=-1|Location.X=1359|Location.Y=451|Color=8388608|FontID=3|Text=C23|Name=Designator|ReadOnlyState=1
|RECORD=41|OwnerIndex=1285|IndexInSheet=-1|OwnerPartId=-1|Location.X=1359|Location.Y=441|Color=8388608|FontID=3|Text=0.1uF|Name=Comment
|RECORD=44|OwnerIndex=1285
|RECORD=45|OwnerIndex=1306|IndexInSheet=-1|Description=Chip Capacitor, 2-Leads, Body 1.60x0.80mm, IPC Low Density|UseComponentLibrary=T|ModelName=CAPC1608X87X45ML20T05|ModelType=PCBLIB|DatafileCount=1|ModelDatafileEntity0=CAPC1608X87X45ML20T05|ModelDatafileKind0=PCBLib|IsCurrent=T|DatalinksLocked=T|DatabaseDatalinksLocked=T
|RECORD=46|OwnerIndex=1307
|RECORD=48|OwnerIndex=1307
|RECORD=41|OwnerIndex=1309|IndexInSheet=-1|OwnerPartId=-1|Color=8388608|FontID=1|Text=2D|Name=Available Preview Images
|RECORD=45|OwnerIndex=1306|IndexInSheet=-1|Description=Chip Capacitor, 2-Leads, Body 1.60x0.80mm, IPC High Density|UseComponentLibrary=T|ModelName=CAPC1608X87X45LL20T05|ModelType=PCBLIB|DatafileCount=1|ModelDatafileEntity0=CAPC1608X87X45LL20T05|ModelDatafileKind0=PCBLib|DatalinksLocked=T|DatabaseDatalinksLocked=T
|RECORD=46|OwnerIndex=1311
|RECORD=48|OwnerIndex=1311
|RECORD=41|OwnerIndex=1313|IndexInSheet=-1|OwnerPartId=-1|Color=8388608|FontID=1|Text=2D|Name=Available Preview Images
|RECORD=45|OwnerIndex=1306|IndexInSheet=-1|Description=Chip Capacitor, 2-Leads, Body 1.60x0.80mm, IPC Medium Density|UseComponentLibrary=T|ModelName=CAPC1608X87X45NL20T05|ModelType=PCBLIB|DatafileCount=1|ModelDatafileEntity0=CAPC1608X87X45NL20T05|ModelDatafileKind0=PCBLib|DatalinksLocked=T|DatabaseDatalinksLocked=T
|RECORD=46|OwnerIndex=1315
|RECORD=48|OwnerIndex=1315
|RECORD=41|OwnerIndex=1317|IndexInSheet=-1|OwnerPartId=-1|Color=8388608|FontID=1|Text=2D|Name=Available Preview Images
|RECORD=1|LibReference=CAP|ComponentDescription=C0603X104K5RACAUTO|PartCount=2|DisplayModeCount=2|IndexInSheet=141|OwnerPartId=-1|Location.X=1410|Location.Y=450|Orientation=1|CurrentPartId=1|SourceLibraryName=Altium Content Vault|TargetFileName=*|AreaColor=11599871|Color=128|PartIDLocked=F|DesignItemId=CMP-2006-00003-1|AllPinCount=2
|RECORD=2|OwnerIndex=1319|OwnerPartId=1|OwnerPartDisplayMode=1|FormalType=1|Electrical=4|PinConglomerate=35|PinLength=10|Location.X=1420|Location.Y=450|Name=1|Designator=1|PinPropagationDelay=0.000000E+000
|RECORD=2|OwnerIndex=1319|OwnerPartId=1|OwnerPartDisplayMode=1|FormalType=1|Electrical=4|PinConglomerate=33|PinLength=10|Location.X=1420|Location.Y=460|Name=2|Designator=2|PinPropagationDelay=0.000000E+000
|RECORD=13|OwnerIndex=1319|IsNotAccesible=T|IndexInSheet=2|OwnerPartId=1|OwnerPartDisplayMode=1|Location.X=1428|Location.Y=450|Corner.X=1412|Corner.Y=450|LineWidth=1|Color=16711680
|RECORD=13|OwnerIndex=1319|IsNotAccesible=T|IndexInSheet=3|OwnerPartId=1|OwnerPartDisplayMode=1|Location.X=1420|Location.Y=454|Corner.X=1420|Corner.Y=460|LineWidth=1|Color=16711680
|RECORD=12|OwnerIndex=1319|IsNotAccesible=T|IndexInSheet=4|OwnerPartId=1|OwnerPartDisplayMode=1|Location.X=1420|Location.Y=470|Radius=16|LineWidth=1|StartAngle=241.000|EndAngle=270.000|Color=16711680
|RECORD=12|OwnerIndex=1319|IsNotAccesible=T|IndexInSheet=5|OwnerPartId=1|OwnerPartDisplayMode=1|Location.X=1420|Location.Y=470|Radius=16|LineWidth=1|StartAngle=270.000|EndAngle=299.000|Color=16711680
|RECORD=2|OwnerIndex=1319|OwnerPartId=1|FormalType=1|Electrical=4|PinConglomerate=35|PinLength=10|Location.X=1420|Location.Y=450|Name=1|Designator=1|PinPropagationDelay=0.000000E+000
|RECORD=2|OwnerIndex=1319|OwnerPartId=1|FormalType=1|Electrical=4|PinConglomerate=33|PinLength=10|Location.X=1420|Location.Y=460|Name=2|Designator=2|PinPropagationDelay=0.000000E+000
|RECORD=13|OwnerIndex=1319|IsNotAccesible=T|IndexInSheet=8|OwnerPartId=1|Location.X=1412|Location.Y=457|Corner.X=1428|Corner.Y=457|LineWidth=1|Color=16711680
|RECORD=13|OwnerIndex=1319|IsNotAccesible=T|IndexInSheet=9|OwnerPartId=1|Location.X=1428|Location.Y=453|Corner.X=1412|Corner.Y=453|LineWidth=1|Color=16711680
|RECORD=6|OwnerIndex=1319|IsNotAccesible=T|IndexInSheet=10|OwnerPartId=1|LineWidth=1|Color=16711680|LocationCount=2|X1=1420|Y1=450|X2=1420|Y2=453
|RECORD=6|OwnerIndex=1319|IsNotAccesible=T|IndexInSheet=11|OwnerPartId=1|LineWidth=1|Color=16711680|LocationCount=2|X1=1420|Y1=460|X2=1420|Y2=457
|RECORD=41|OwnerIndex=1319|IndexInSheet=12|OwnerPartId=-1|Location.X=1411|Location.Y=472|Color=8388608|FontID=1|IsHidden=T|Text=Kemet|Name=Manufacturer
|RECORD=41|OwnerIndex=1319|IndexInSheet=13|OwnerPartId=-1|Location.X=1411|Location.Y=472|Color=8388608|FontID=1|IsHidden=T|Text=C0603X104K5RACAUTO|Name=Part Number
|RECORD=34|OwnerIndex=1319|IndexInSheet=-1|OwnerPartId=-1|Location.X=1429|Location.Y=451|Color=8388608|FontID=3|Text=C24|Name=Designator|ReadOnlyState=1
|RECORD=41|OwnerIndex=1319|IndexInSheet=-1|OwnerPartId=-1|Location.X=1429|Location.Y=441|Color=8388608|FontID=3|Text=0.1uF|Name=Comment
|RECORD=44|OwnerIndex=1319
|RECORD=45|OwnerIndex=1340|IndexInSheet=-1|Description=Chip Capacitor, 2-Leads, Body 1.60x0.80mm, IPC Low Density|UseComponentLibrary=T|ModelName=CAPC1608X87X45ML20T05|ModelType=PCBLIB|DatafileCount=1|ModelDatafileEntity0=CAPC1608X87X45ML20T05|ModelDatafileKind0=PCBLib|IsCurrent=T|DatalinksLocked=T|DatabaseDatalinksLocked=T
|RECORD=46|OwnerIndex=1341
|RECORD=48|OwnerIndex=1341
|RECORD=41|OwnerIndex=1343|IndexInSheet=-1|OwnerPartId=-1|Color=8388608|FontID=1|Text=2D|Name=Available Preview Images
|RECORD=45|OwnerIndex=1340|IndexInSheet=-1|Description=Chip Capacitor, 2-Leads, Body 1.60x0.80mm, IPC High Density|UseComponentLibrary=T|ModelName=CAPC1608X87X45LL20T05|ModelType=PCBLIB|DatafileCount=1|ModelDatafileEntity0=CAPC1608X87X45LL20T05|ModelDatafileKind0=PCBLib|DatalinksLocked=T|DatabaseDatalinksLocked=T
|RECORD=46|OwnerIndex=1345
|RECORD=48|OwnerIndex=1345
|RECORD=41|OwnerIndex=1347|IndexInSheet=-1|OwnerPartId=-1|Color=8388608|FontID=1|Text=2D|Name=Available Preview Images
|RECORD=45|OwnerIndex=1340|IndexInSheet=-1|Description=Chip Capacitor, 2-Leads, Body 1.60x0.80mm, IPC Medium Density|UseComponentLibrary=T|ModelName=CAPC1608X87X45NL20T05|ModelType=PCBLIB|DatafileCount=1|ModelDatafileEntity0=CAPC1608X87X45NL20T05|ModelDatafileKind0=PCBLib|DatalinksLocked=T|DatabaseDatalinksLocked=T
|RECORD=46|OwnerIndex=1349
|RECORD=48|OwnerIndex=1349
|RECORD=41|OwnerIndex=1351|IndexInSheet=-1|OwnerPartId=-1|Color=8388608|FontID=1|Text=2D|Name=Available Preview Images
|RECORD=17|IndexInSheet=142|OwnerPartId=-1|Style=4|ShowNetName=T|Location.X=1350|Location.Y=420|Orientation=3|Color=128|FontID=1|Text=GND
|RECORD=17|IndexInSheet=143|OwnerPartId=-1|Style=4|ShowNetName=T|Location.X=1420|Location.Y=420|Orientation=3|Color=128|FontID=1|Text=GND
|RECORD=17|IndexInSheet=144|OwnerPartId=-1|ShowNetName=T|Location.X=1350|Location.Y=590|Orientation=1|Color=128|FontID=1|Text=+3.3V_CLEAN
|RECORD=17|IndexInSheet=145|OwnerPartId=-1|ShowNetName=T|Location.X=1420|Location.Y=590|Orientation=1|Color=128|FontID=1|Text=+3.3V_CLEAN
|RECORD=17|IndexInSheet=146|OwnerPartId=-1|ShowNetName=T|Location.X=1090|Location.Y=300|Orientation=1|Color=128|FontID=1|Text=+3.3V
|RECORD=17|IndexInSheet=147|OwnerPartId=-1|Style=4|ShowNetName=T|Location.X=1140|Location.Y=150|Orientation=3|Color=128|FontID=1|Text=GND
|RECORD=17|IndexInSheet=148|OwnerPartId=-1|ShowNetName=T|Location.X=1070|Location.Y=210|Orientation=2|Color=255|FontID=1|Text=EXT_EEPROM_WP|IsCrossSheetConnector=T
|RECORD=1|LibReference=RES-2|ComponentDescription=Chip Resistor, 10 KOhm, +/- 1%, 0.1 W, -55 to 155 degC, 0603 (1608 Metric), RoHS, Tape and Reel RMCF0603FT10K0|PartCount=2|DisplayModeCount=1|IndexInSheet=149|OwnerPartId=-1|Location.X=1090|Location.Y=250|Orientation=1|CurrentPartId=1|LibraryPath=*|SourceLibraryName=Altium Content Vault|TargetFileName=*|AreaColor=11599871|Color=128|PartIDLocked=T|DesignItemId=CMP-2000-06990-1|AllPinCount=2
|RECORD=2|OwnerIndex=1360|OwnerPartId=1|FormalType=1|Electrical=4|PinConglomerate=33|PinLength=10|Location.X=1090|Location.Y=270|Name=2|Designator=2|PinPropagationDelay=0.000000E+000
|RECORD=2|OwnerIndex=1360|OwnerPartId=1|FormalType=1|Electrical=4|PinConglomerate=35|PinLength=10|Location.X=1090|Location.Y=250|Name=1|Designator=1|PinPropagationDelay=0.000000E+000
|RECORD=6|OwnerIndex=1360|IsNotAccesible=T|IndexInSheet=2|OwnerPartId=1|LineWidth=1|Color=16711680|LocationCount=10|X1=1090|Y1=270|X2=1090|Y2=266|X3=1092|Y3=265|X4=1088|Y4=263|X5=1092|Y5=261|X6=1088|Y6=259|X7=1092|Y7=257|X8=1088|Y8=255|X9=1090|Y9=254|X10=1090|Y10=250
|RECORD=41|OwnerIndex=1360|IndexInSheet=3|OwnerPartId=-1|Location.X=1087|Location.Y=282|Color=8388608|FontID=1|IsHidden=T|Text=0603(1608Metric)|Name=Package / Case
|RECORD=41|OwnerIndex=1360|IndexInSheet=4|OwnerPartId=-1|Location.X=1087|Location.Y=282|Color=8388608|FontID=1|IsHidden=T|Text=01/2017|Name=Datasheet Version
|RECORD=41|OwnerIndex=1360|IndexInSheet=5|OwnerPartId=-1|Location.X=1087|Location.Y=282|Color=8388608|FontID=1|IsHidden=T|Text=10k|Name=Resistance (Ohms)
|RECORD=41|OwnerIndex=1360|IndexInSheet=6|OwnerPartId=-1|Location.X=1087|Location.Y=282|Color=8388608|FontID=1|IsHidden=T|Text=AutomotiveAEC-Q200|Name=Features
|RECORD=41|OwnerIndex=1360|IndexInSheet=7|OwnerPartId=-1|Location.X=1087|Location.Y=282|Color=8388608|FontID=1|IsHidden=T|Text=CutTape(CT)|Name=Packaging
|RECORD=41|OwnerIndex=1360|IndexInSheet=8|OwnerPartId=-1|Location.X=1087|Location.Y=282|Color=8388608|FontID=1|IsHidden=T|Text=RMCF|Name=Series
|RECORD=41|OwnerIndex=1360|IndexInSheet=9|OwnerPartId=-1|Location.X=1087|Location.Y=282|Color=8388608|FontID=1|IsHidden=T|Text=0.022"(0.55mm)|Name=Height
|RECORD=41|OwnerIndex=1360|IndexInSheet=10|OwnerPartId=-1|Location.X=1087|Location.Y=282|Color=8388608|FontID=1|IsHidden=T|Text=±1%|Name=Tolerance
|RECORD=41|OwnerIndex=1360|IndexInSheet=11|OwnerPartId=-1|Location.X=1087|Location.Y=282|Color=8388608|FontID=5|IsHidden=T|Text=https://www.seielect.com/|Name=Manufacturer URL
|RECORD=41|OwnerIndex=1360|IndexInSheet=12|OwnerPartId=-1|Location.X=1087|Location.Y=282|Color=8388608|FontID=5|IsHidden=T|Text=https://www.seielect.com/Catalog/SEI-RMCF_RMCP.pdf|Name=Datasheet URL
|RECORD=41|OwnerIndex=1360|IndexInSheet=13|OwnerPartId=-1|Location.X=1087|Location.Y=282|Color=8388608|FontID=1|IsHidden=T|Text=0603|Name=Supplier Device Package
|RECORD=41|OwnerIndex=1360|IndexInSheet=14|OwnerPartId=-1|Location.X=1087|Location.Y=282|Color=8388608|FontID=1|IsHidden=T|Text=2|Name=Number of Terminations
|RECORD=41|OwnerIndex=1360|IndexInSheet=15|OwnerPartId=-1|Location.X=1087|Location.Y=282|Color=8388608|FontID=1|IsHidden=T|Text=ChipResistor-SurfaceMount|Name=Family
|RECORD=41|OwnerIndex=1360|IndexInSheet=16|OwnerPartId=-1|Location.X=1087|Location.Y=282|Color=8388608|FontID=1|IsHidden=T|Text=0603|Name=Package Reference
|RECORD=41|OwnerIndex=1360|IndexInSheet=17|OwnerPartId=-1|Location.X=1087|Location.Y=282|Color=8388608|FontID=1|IsHidden=T|Text=0.061"Lx0.031"W(1.55mmx0.80mm)|Name=Size / Dimension
|RECORD=41|OwnerIndex=1360|IndexInSheet=18|OwnerPartId=-1|Location.X=1087|Location.Y=282|Color=8388608|FontID=1|IsHidden=T|Text=SurfaceMount|Name=Mounting Technology
|RECORD=41|OwnerIndex=1360|IndexInSheet=19|OwnerPartId=-1|Location.X=1087|Location.Y=282|Color=8388608|FontID=1|IsHidden=T|Text=2-Pin Surface Mount Device, Body 1.55 x 0.8 mm|Name=Package Description
|RECORD=41|OwnerIndex=1360|IndexInSheet=20|OwnerPartId=-1|Location.X=1087|Location.Y=282|Color=8388608|FontID=1|IsHidden=T|Text=-55°C~155°C|Name=Operating Temperature
|RECORD=41|OwnerIndex=1360|IndexInSheet=21|OwnerPartId=-1|Location.X=1087|Location.Y=282|Color=8388608|FontID=1|IsHidden=T|Text=±100ppm/°C|Name=Temperature Coefficient
|RECORD=41|OwnerIndex=1360|IndexInSheet=22|OwnerPartId=-1|Location.X=1087|Location.Y=282|Color=8388608|FontID=1|IsHidden=T|Text=ThickFilm|Name=Composition
|RECORD=41|OwnerIndex=1360|IndexInSheet=23|OwnerPartId=-1|Location.X=1087|Location.Y=282|Color=8388608|FontID=1|IsHidden=T|Text=0.1W,1/10W|Name=Power (Watts)
|RECORD=41|OwnerIndex=1360|IndexInSheet=24|OwnerPartId=-1|Location.X=1087|Location.Y=282|Color=8388608|FontID=1|IsHidden=T|Text=Stackpole-Electronics-Inc.|Name=Manufacturer
|RECORD=41|OwnerIndex=1360|IndexInSheet=25|OwnerPartId=-1|Location.X=1087|Location.Y=282|Color=8388608|FontID=1|IsHidden=T|Text=Resistors|Name=Category
|RECORD=34|OwnerIndex=1360|IndexInSheet=-1|OwnerPartId=-1|Location.X=1093|Location.Y=261|Color=8388608|FontID=1|Text=R37|Name=Designator|ReadOnlyState=1
|RECORD=41|OwnerIndex=1360|IndexInSheet=-1|OwnerPartId=-1|Location.X=1093|Location.Y=251|Color=8388608|FontID=1|Text=10K|Name=Comment
|RECORD=44|OwnerIndex=1360
|RECORD=45|OwnerIndex=1391|IndexInSheet=-1|Description=Chip Resistor, 2-Leads, Body 1.7x0.95mm, IPC High Density|UseComponentLibrary=T|ModelName=RESC1608X55X30LL15T20|ModelType=PCBLIB|DatafileCount=1|ModelDatafileEntity0=RESC1608X55X30LL15T20|ModelDatafileKind0=PCBLib|IsCurrent=T|DatalinksLocked=T|DatabaseDatalinksLocked=T
|RECORD=46|OwnerIndex=1392
|RECORD=48|OwnerIndex=1392
|RECORD=41|OwnerIndex=1394|IndexInSheet=-1|OwnerPartId=-1|Color=8388608|FontID=1|Text=2D|Name=Available Preview Images
|RECORD=45|OwnerIndex=1391|IndexInSheet=-1|Description=Chip Resistor, 2-Leads, Body 1.7x0.95mm, IPC Low Density|UseComponentLibrary=T|ModelName=RESC1608X55X30ML15T20|ModelType=PCBLIB|DatafileCount=1|ModelDatafileEntity0=RESC1608X55X30ML15T20|ModelDatafileKind0=PCBLib|DatalinksLocked=T|DatabaseDatalinksLocked=T
|RECORD=46|OwnerIndex=1396
|RECORD=48|OwnerIndex=1396
|RECORD=41|OwnerIndex=1398|IndexInSheet=-1|OwnerPartId=-1|Color=8388608|FontID=1|Text=2D|Name=Available Preview Images
|RECORD=45|OwnerIndex=1391|IndexInSheet=-1|Description=Chip Resistor, 2-Leads, Body 1.7x0.95mm, IPC Medium Density|UseComponentLibrary=T|ModelName=RESC1608X55X30NL15T20|ModelType=PCBLIB|DatafileCount=1|ModelDatafileEntity0=RESC1608X55X30NL15T20|ModelDatafileKind0=PCBLib|DatalinksLocked=T|DatabaseDatalinksLocked=T
|RECORD=46|OwnerIndex=1400
|RECORD=48|OwnerIndex=1400
|RECORD=41|OwnerIndex=1402|IndexInSheet=-1|OwnerPartId=-1|Color=8388608|FontID=1|Text=2D|Name=Available Preview Images
|RECORD=27|IndexInSheet=150|OwnerPartId=-1|LineWidth=1|Color=8388608|LocationCount=4|X1=220|Y1=700|X2=220|Y2=690|X3=170|Y3=690|X4=170|Y4=700
|RECORD=27|IndexInSheet=151|OwnerPartId=-1|LineWidth=1|Color=8388608|LocationCount=4|X1=170|Y1=730|X2=170|Y2=740|X3=220|Y3=740|X4=510|Y4=740
|RECORD=27|IndexInSheet=152|OwnerPartId=-1|LineWidth=1|Color=8388608|LocationCount=4|X1=220|Y1=880|X2=220|Y2=870|X3=170|Y3=870|X4=170|Y4=880
|RECORD=27|IndexInSheet=153|OwnerPartId=-1|LineWidth=1|Color=8388608|LocationCount=4|X1=170|Y1=910|X2=170|Y2=920|X3=220|Y3=920|X4=510|Y4=920
|RECORD=27|IndexInSheet=154|OwnerPartId=-1|LineWidth=1|Color=8388608|LocationCount=4|X1=250|Y1=300|X2=250|Y2=290|X3=200|Y3=290|X4=200|Y4=300
|RECORD=27|IndexInSheet=155|OwnerPartId=-1|LineWidth=1|Color=8388608|LocationCount=4|X1=200|Y1=330|X2=200|Y2=340|X3=250|Y3=340|X4=410|Y4=340
|RECORD=27|IndexInSheet=156|OwnerPartId=-1|LineWidth=1|Color=8388608|LocationCount=4|X1=320|Y1=700|X2=320|Y2=690|X3=270|Y3=690|X4=270|Y4=700
|RECORD=27|IndexInSheet=157|OwnerPartId=-1|LineWidth=1|Color=8388608|LocationCount=4|X1=270|Y1=770|X2=270|Y2=750|X3=320|Y3=750|X4=510|Y4=750
|RECORD=27|IndexInSheet=158|OwnerPartId=-1|LineWidth=1|Color=8388608|LocationCount=4|X1=320|Y1=880|X2=320|Y2=870|X3=270|Y3=870|X4=270|Y4=880
|RECORD=27|IndexInSheet=159|OwnerPartId=-1|LineWidth=1|Color=8388608|LocationCount=4|X1=270|Y1=950|X2=270|Y2=930|X3=320|Y3=930|X4=510|Y4=930
|RECORD=27|IndexInSheet=160|OwnerPartId=-1|LineWidth=1|Color=8388608|LocationCount=2|X1=410|Y1=230|X2=360|Y2=230
|RECORD=27|IndexInSheet=161|OwnerPartId=-1|LineWidth=1|Color=8388608|LocationCount=2|X1=410|Y1=260|X2=360|Y2=260
|RECORD=27|IndexInSheet=162|OwnerPartId=-1|LineWidth=1|Color=8388608|LocationCount=2|X1=410|Y1=270|X2=360|Y2=270
|RECORD=27|IndexInSheet=163|OwnerPartId=-1|LineWidth=1|Color=8388608|LocationCount=2|X1=410|Y1=310|X2=360|Y2=310
|RECORD=27|IndexInSheet=164|OwnerPartId=-1|LineWidth=1|Color=8388608|LocationCount=2|X1=410|Y1=320|X2=360|Y2=320
|RECORD=27|IndexInSheet=165|OwnerPartId=-1|LineWidth=1|Color=8388608|LocationCount=2|X1=360|Y1=330|X2=410|Y2=330
|RECORD=27|IndexInSheet=166|OwnerPartId=-1|LineWidth=1|Color=8388608|LocationCount=3|X1=410|Y1=350|X2=390|Y2=350|X3=390|Y3=210
|RECORD=27|IndexInSheet=167|OwnerPartId=-1|LineWidth=1|Color=8388608|LocationCount=2|X1=510|Y1=720|X2=420|Y2=720
|RECORD=27|IndexInSheet=168|OwnerPartId=-1|LineWidth=1|Color=8388608|LocationCount=2|X1=510|Y1=730|X2=420|Y2=730
|RECORD=27|IndexInSheet=169|OwnerPartId=-1|LineWidth=1|Color=8388608|LocationCount=2|X1=510|Y1=900|X2=420|Y2=900
|RECORD=27|IndexInSheet=170|OwnerPartId=-1|LineWidth=1|Color=8388608|LocationCount=2|X1=510|Y1=910|X2=420|Y2=910
|RECORD=27|IndexInSheet=171|OwnerPartId=-1|LineWidth=1|Color=8388608|LocationCount=2|X1=600|Y1=230|X2=660|Y2=230
|RECORD=27|IndexInSheet=172|OwnerPartId=-1|LineWidth=1|Color=8388608|LocationCount=2|X1=600|Y1=240|X2=660|Y2=240
|RECORD=27|IndexInSheet=173|OwnerPartId=-1|LineWidth=1|Color=8388608|LocationCount=2|X1=600|Y1=250|X2=660|Y2=250
|RECORD=27|IndexInSheet=174|OwnerPartId=-1|LineWidth=1|Color=8388608|LocationCount=2|X1=600|Y1=260|X2=660|Y2=260
|RECORD=27|IndexInSheet=175|OwnerPartId=-1|LineWidth=1|Color=8388608|LocationCount=2|X1=600|Y1=270|X2=660|Y2=270
|RECORD=27|IndexInSheet=176|OwnerPartId=-1|LineWidth=1|Color=8388608|LocationCount=2|X1=600|Y1=280|X2=660|Y2=280
|RECORD=27|IndexInSheet=177|OwnerPartId=-1|LineWidth=1|Color=8388608|LocationCount=3|X1=600|Y1=330|X2=620|Y2=330|X3=620|Y3=210
|RECORD=27|IndexInSheet=178|OwnerPartId=-1|LineWidth=1|Color=8388608|LocationCount=7|X1=880|Y1=350|X2=900|Y2=350|X3=900|Y3=290|X4=800|Y4=290|X5=800|Y5=340|X6=760|Y6=340|X7=600|Y7=340
|RECORD=27|IndexInSheet=179|OwnerPartId=-1|LineWidth=1|Color=8388608|LocationCount=3|X1=820|Y1=350|X2=710|Y2=350|X3=600|Y3=350
|RECORD=27|IndexInSheet=180|OwnerPartId=-1|LineWidth=1|Color=8388608|LocationCount=3|X1=600|Y1=360|X2=620|Y2=360|X3=620|Y3=370
|RECORD=27|IndexInSheet=181|OwnerPartId=-1|LineWidth=1|Color=8388608|LocationCount=2|X1=760|Y1=720|X2=670|Y2=720
|RECORD=27|IndexInSheet=182|OwnerPartId=-1|LineWidth=1|Color=8388608|LocationCount=2|X1=760|Y1=730|X2=670|Y2=730
|RECORD=27|IndexInSheet=183|OwnerPartId=-1|LineWidth=1|Color=8388608|LocationCount=2|X1=760|Y1=740|X2=670|Y2=740
|RECORD=27|IndexInSheet=184|OwnerPartId=-1|LineWidth=1|Color=8388608|LocationCount=3|X1=670|Y1=750|X2=690|Y2=750|X3=690|Y3=680
|RECORD=27|IndexInSheet=185|OwnerPartId=-1|LineWidth=1|Color=8388608|LocationCount=2|X1=760|Y1=900|X2=670|Y2=900
|RECORD=27|IndexInSheet=186|OwnerPartId=-1|LineWidth=1|Color=8388608|LocationCount=2|X1=760|Y1=910|X2=670|Y2=910
|RECORD=27|IndexInSheet=187|OwnerPartId=-1|LineWidth=1|Color=8388608|LocationCount=2|X1=760|Y1=920|X2=670|Y2=920
|RECORD=27|IndexInSheet=188|OwnerPartId=-1|LineWidth=1|Color=8388608|LocationCount=3|X1=670|Y1=930|X2=690|Y2=930|X3=690|Y3=860
|RECORD=27|IndexInSheet=189|OwnerPartId=-1|LineWidth=1|Color=8388608|LocationCount=4|X1=710|Y1=300|X2=710|Y2=290|X3=760|Y3=290|X4=760|Y4=280
|RECORD=27|IndexInSheet=190|OwnerPartId=-1|LineWidth=1|Color=8388608|LocationCount=2|X1=890|Y1=730|X2=920|Y2=730
|RECORD=27|IndexInSheet=191|OwnerPartId=-1|LineWidth=1|Color=8388608|LocationCount=2|X1=890|Y1=760|X2=920|Y2=760
|RECORD=27|IndexInSheet=192|OwnerPartId=-1|LineWidth=1|Color=8388608|LocationCount=3|X1=1050|Y1=850|X2=1050|Y2=780|X3=890|Y3=780
|RECORD=27|IndexInSheet=193|OwnerPartId=-1|LineWidth=1|Color=8388608|LocationCount=2|X1=890|Y1=800|X2=920|Y2=800
|RECORD=27|IndexInSheet=194|OwnerPartId=-1|LineWidth=1|Color=8388608|LocationCount=2|X1=890|Y1=830|X2=920|Y2=830
|RECORD=27|IndexInSheet=195|OwnerPartId=-1|LineWidth=1|Color=8388608|LocationCount=2|X1=980|Y1=850|X2=890|Y2=850
|RECORD=27|IndexInSheet=196|OwnerPartId=-1|LineWidth=1|Color=8388608|LocationCount=3|X1=970|Y1=730|X2=1070|Y2=730|X3=1070|Y3=760
|RECORD=27|IndexInSheet=197|OwnerPartId=-1|LineWidth=1|Color=8388608|LocationCount=3|X1=970|Y1=760|X2=1070|Y2=760|X3=1070|Y3=850
|RECORD=27|IndexInSheet=198|OwnerPartId=-1|LineWidth=1|Color=8388608|LocationCount=3|X1=970|Y1=800|X2=1000|Y2=800|X3=1000|Y3=830
|RECORD=27|IndexInSheet=199|OwnerPartId=-1|LineWidth=1|Color=8388608|LocationCount=3|X1=970|Y1=830|X2=1000|Y2=830|X3=1000|Y3=850
|RECORD=27|IndexInSheet=200|OwnerPartId=-1|LineWidth=1|Color=8388608|LocationCount=3|X1=990|Y1=850|X2=990|Y2=820|X3=1160|Y3=820
|RECORD=27|IndexInSheet=201|OwnerPartId=-1|LineWidth=1|Color=8388608|LocationCount=3|X1=1060|Y1=850|X2=1060|Y2=830|X3=1160|Y3=830
|RECORD=27|IndexInSheet=202|OwnerPartId=-1|LineWidth=1|Color=8388608|LocationCount=4|X1=1220|Y1=720|X2=1220|Y2=700|X3=1240|Y3=700|X4=1240|Y4=720
|RECORD=27|IndexInSheet=203|OwnerPartId=-1|LineWidth=1|Color=8388608|LocationCount=5|X1=1310|Y1=820|X2=1370|Y2=820|X3=1370|Y3=870|X4=1220|Y4=870|X5=1220|Y5=860
|RECORD=27|IndexInSheet=204|OwnerPartId=-1|LineWidth=1|Color=8388608|LocationCount=6|X1=1240|Y1=860|X2=1240|Y2=930|X3=1380|Y3=930|X4=1390|Y4=930|X5=1430|Y5=930|X6=1430|Y6=940
|RECORD=27|IndexInSheet=205|OwnerPartId=-1|LineWidth=1|Color=8388608|LocationCount=2|X1=1310|Y1=750|X2=1320|Y2=750
|RECORD=27|IndexInSheet=206|OwnerPartId=-1|LineWidth=1|Color=8388608|LocationCount=4|X1=1450|Y1=780|X2=1330|Y2=780|X3=1330|Y3=770|X4=1310|Y4=770
|RECORD=27|IndexInSheet=207|OwnerPartId=-1|LineWidth=1|Color=8388608|LocationCount=2|X1=1310|Y1=790|X2=1450|Y2=790
|RECORD=27|IndexInSheet=208|OwnerPartId=-1|LineWidth=1|Color=8388608|LocationCount=3|X1=1370|Y1=750|X2=1380|Y2=750|X3=1380|Y3=930
|RECORD=27|IndexInSheet=209|OwnerPartId=-1|LineWidth=1|Color=8388608|LocationCount=4|X1=1390|Y1=900|X2=1390|Y2=890|X3=1430|Y3=890|X4=1430|Y4=900
|RECORD=27|IndexInSheet=210|OwnerPartId=-1|LineWidth=1|Color=8388608|LocationCount=3|X1=1450|Y1=760|X2=1440|Y2=760|X3=1440|Y3=750
|RECORD=27|IndexInSheet=211|OwnerPartId=-1|LineWidth=1|Color=8388608|LocationCount=2|X1=170|Y1=770|X2=170|Y2=740
|RECORD=27|IndexInSheet=212|OwnerPartId=-1|LineWidth=1|Color=8388608|LocationCount=2|X1=170|Y1=950|X2=170|Y2=920
|RECORD=27|IndexInSheet=213|OwnerPartId=-1|LineWidth=1|Color=8388608|LocationCount=2|X1=200|Y1=340|X2=200|Y2=370
|RECORD=27|IndexInSheet=214|OwnerPartId=-1|LineWidth=1|Color=8388608|LocationCount=2|X1=220|Y1=730|X2=220|Y2=740
|RECORD=27|IndexInSheet=215|OwnerPartId=-1|LineWidth=1|Color=8388608|LocationCount=2|X1=220|Y1=910|X2=220|Y2=920
|RECORD=27|IndexInSheet=216|OwnerPartId=-1|LineWidth=1|Color=8388608|LocationCount=2|X1=250|Y1=330|X2=250|Y2=340
|RECORD=27|IndexInSheet=217|OwnerPartId=-1|LineWidth=1|Color=8388608|LocationCount=2|X1=270|Y1=750|X2=270|Y2=730
|RECORD=27|IndexInSheet=218|OwnerPartId=-1|LineWidth=1|Color=8388608|LocationCount=2|X1=270|Y1=930|X2=270|Y2=910
|RECORD=27|IndexInSheet=219|OwnerPartId=-1|LineWidth=1|Color=8388608|LocationCount=2|X1=320|Y1=730|X2=320|Y2=750
|RECORD=27|IndexInSheet=220|OwnerPartId=-1|LineWidth=1|Color=8388608|LocationCount=2|X1=320|Y1=910|X2=320|Y2=930
|RECORD=27|IndexInSheet=221|OwnerPartId=-1|LineWidth=1|Color=8388608|LocationCount=2|X1=710|Y1=330|X2=710|Y2=350
|RECORD=27|IndexInSheet=222|OwnerPartId=-1|LineWidth=1|Color=8388608|LocationCount=2|X1=760|Y1=290|X2=760|Y2=300
|RECORD=27|IndexInSheet=223|OwnerPartId=-1|LineWidth=1|Color=8388608|LocationCount=2|X1=760|Y1=330|X2=760|Y2=340
|RECORD=27|IndexInSheet=224|OwnerPartId=-1|LineWidth=1|Color=8388608|LocationCount=2|X1=1370|Y1=250|X2=1290|Y2=250
|RECORD=27|IndexInSheet=225|OwnerPartId=-1|LineWidth=1|Color=8388608|LocationCount=2|X1=1290|Y1=240|X2=1370|Y2=240
|RECORD=27|IndexInSheet=226|OwnerPartId=-1|LineWidth=1|Color=8388608|LocationCount=3|X1=1290|Y1=210|X2=1330|Y2=210|X3=1330|Y3=150
|RECORD=27|IndexInSheet=227|OwnerPartId=-1|LineWidth=1|Color=8388608|LocationCount=3|X1=1180|Y1=250|X2=1140|Y2=250|X3=1140|Y3=300
|RECORD=27|IndexInSheet=228|OwnerPartId=-1|LineWidth=1|Color=8388608|LocationCount=2|X1=1140|Y1=250|X2=1140|Y2=190
|RECORD=27|IndexInSheet=229|OwnerPartId=-1|LineWidth=1|Color=8388608|LocationCount=5|X1=1300|Y1=480|X2=1320|Y2=480|X3=1320|Y3=470|X4=1320|Y4=460|X5=1320|Y5=420
|RECORD=27|IndexInSheet=230|OwnerPartId=-1|LineWidth=1|Color=8388608|LocationCount=2|X1=1300|Y1=470|X2=1320|Y2=470
|RECORD=27|IndexInSheet=231|OwnerPartId=-1|LineWidth=1|Color=8388608|LocationCount=2|X1=1300|Y1=460|X2=1320|Y2=460
|RECORD=27|IndexInSheet=232|OwnerPartId=-1|LineWidth=1|Color=8388608|LocationCount=4|X1=1300|Y1=540|X2=1350|Y2=540|X3=1350|Y3=510|X4=1350|Y4=470
|RECORD=27|IndexInSheet=233|OwnerPartId=-1|LineWidth=1|Color=8388608|LocationCount=2|X1=1300|Y1=510|X2=1350|Y2=510
|RECORD=27|IndexInSheet=234|OwnerPartId=-1|LineWidth=1|Color=8388608|LocationCount=2|X1=1350|Y1=440|X2=1350|Y2=420
|RECORD=27|IndexInSheet=235|OwnerPartId=-1|LineWidth=1|Color=8388608|LocationCount=2|X1=1420|Y1=440|X2=1420|Y2=420
|RECORD=27|IndexInSheet=236|OwnerPartId=-1|LineWidth=1|Color=8388608|LocationCount=2|X1=1350|Y1=540|X2=1350|Y2=590
|RECORD=27|IndexInSheet=237|OwnerPartId=-1|LineWidth=1|Color=8388608|LocationCount=2|X1=1420|Y1=550|X2=1420|Y2=590
|RECORD=27|IndexInSheet=238|OwnerPartId=-1|LineWidth=1|Color=8388608|LocationCount=3|X1=1300|Y1=550|X2=1420|Y2=550|X3=1420|Y3=470
|RECORD=27|IndexInSheet=239|OwnerPartId=-1|LineWidth=1|Color=8388608|LocationCount=2|X1=1180|Y1=550|X2=1120|Y2=550
|RECORD=27|IndexInSheet=240|OwnerPartId=-1|LineWidth=1|Color=8388608|LocationCount=2|X1=1180|Y1=540|X2=1120|Y2=540
|RECORD=27|IndexInSheet=241|OwnerPartId=-1|LineWidth=1|Color=8388608|LocationCount=2|X1=1090|Y1=300|X2=1090|Y2=280
|RECORD=27|IndexInSheet=242|OwnerPartId=-1|LineWidth=1|Color=8388608|LocationCount=3|X1=1180|Y1=210|X2=1090|Y2=210|X3=1090|Y3=240
|RECORD=27|IndexInSheet=243|OwnerPartId=-1|LineWidth=1|Color=8388608|LocationCount=2|X1=1140|Y1=160|X2=1140|Y2=150
|RECORD=27|IndexInSheet=244|OwnerPartId=-1|LineWidth=1|Color=8388608|LocationCount=2|X1=1090|Y1=210|X2=1070|Y2=210
|RECORD=41|IndexInSheet=245|OwnerPartId=-1|Color=8388608|FontID=1|IsHidden=T|Name=ConfigurationParameters|ReadOnlyState=1
|RECORD=41|IndexInSheet=246|OwnerPartId=-1|Color=8388608|FontID=1|IsHidden=T|Name=ConfiguratorName|ReadOnlyState=1
|RECORD=41|IndexInSheet=247|OwnerPartId=-1|Color=8388608|FontID=1|IsHidden=T|Name=VersionControl_RevNumber|ReadOnlyState=1
|RECORD=41|IndexInSheet=248|OwnerPartId=-1|Color=8388608|FontID=1|IsHidden=T|Name=IsUserConfigurable|ReadOnlyState=1
|RECORD=41|IndexInSheet=249|OwnerPartId=-1|Color=8388608|FontID=1|IsHidden=T|Name=VersionControl_ProjFolderRevNumber|ReadOnlyState=1
|RECORD=41|IndexInSheet=250|OwnerPartId=-1|Color=8388608|FontID=1|IsHidden=T|Name=SPICEModelCache|ReadOnlyState=1
|RECORD=4|IndexInSheet=251|OwnerPartId=-1|Location.X=1190|Location.Y=296|Color=8388608|FontID=4|Text=EEPROM
|RECORD=29|IndexInSheet=-1|OwnerPartId=-1|Location.X=170|Location.Y=690|Color=128
|RECORD=29|IndexInSheet=-1|OwnerPartId=-1|Location.X=170|Location.Y=740|Color=128
|RECORD=29|IndexInSheet=-1|OwnerPartId=-1|Location.X=170|Location.Y=870|Color=128
|RECORD=29|IndexInSheet=-1|OwnerPartId=-1|Location.X=170|Location.Y=920|Color=128
|RECORD=29|IndexInSheet=-1|OwnerPartId=-1|Location.X=200|Location.Y=290|Color=128
|RECORD=29|IndexInSheet=-1|OwnerPartId=-1|Location.X=200|Location.Y=340|Color=128
|RECORD=29|IndexInSheet=-1|OwnerPartId=-1|Location.X=220|Location.Y=740|Color=128
|RECORD=29|IndexInSheet=-1|OwnerPartId=-1|Location.X=220|Location.Y=920|Color=128
|RECORD=29|IndexInSheet=-1|OwnerPartId=-1|Location.X=250|Location.Y=340|Color=128
|RECORD=29|IndexInSheet=-1|OwnerPartId=-1|Location.X=270|Location.Y=690|Color=128
|RECORD=29|IndexInSheet=-1|OwnerPartId=-1|Location.X=270|Location.Y=750|Color=128
|RECORD=29|IndexInSheet=-1|OwnerPartId=-1|Location.X=270|Location.Y=870|Color=128
|RECORD=29|IndexInSheet=-1|OwnerPartId=-1|Location.X=270|Location.Y=930|Color=128
|RECORD=29|IndexInSheet=-1|OwnerPartId=-1|Location.X=320|Location.Y=750|Color=128
|RECORD=29|IndexInSheet=-1|OwnerPartId=-1|Location.X=320|Location.Y=930|Color=128
|RECORD=29|IndexInSheet=-1|OwnerPartId=-1|Location.X=710|Location.Y=350|Color=128
|RECORD=29|IndexInSheet=-1|OwnerPartId=-1|Location.X=760|Location.Y=290|Color=128
|RECORD=29|IndexInSheet=-1|OwnerPartId=-1|Location.X=760|Location.Y=340|Color=128
|RECORD=29|IndexInSheet=-1|OwnerPartId=-1|Location.X=1000|Location.Y=830|Color=128
|RECORD=29|IndexInSheet=-1|OwnerPartId=-1|Location.X=1070|Location.Y=760|Color=128
|RECORD=29|IndexInSheet=-1|OwnerPartId=-1|Location.X=1090|Location.Y=210|Color=128
|RECORD=29|IndexInSheet=-1|OwnerPartId=-1|Location.X=1140|Location.Y=250|Color=128
|RECORD=29|IndexInSheet=-1|OwnerPartId=-1|Location.X=1240|Location.Y=700|Color=128
|RECORD=29|IndexInSheet=-1|OwnerPartId=-1|Location.X=1320|Location.Y=460|Color=128
|RECORD=29|IndexInSheet=-1|OwnerPartId=-1|Location.X=1320|Location.Y=470|Color=128
|RECORD=29|IndexInSheet=-1|OwnerPartId=-1|Location.X=1350|Location.Y=510|Color=128
|RECORD=29|IndexInSheet=-1|OwnerPartId=-1|Location.X=1350|Location.Y=540|Color=128
|RECORD=29|IndexInSheet=-1|OwnerPartId=-1|Location.X=1380|Location.Y=930|Color=128
|RECORD=29|IndexInSheet=-1|OwnerPartId=-1|Location.X=1390|Location.Y=930|Color=128
|RECORD=29|IndexInSheet=-1|OwnerPartId=-1|Location.X=1420|Location.Y=550|Color=128
|RECORD=29|IndexInSheet=-1|OwnerPartId=-1|Location.X=1430|Location.Y=890|Color=128
|RECORD=29|IndexInSheet=-1|OwnerPartId=-1|Location.X=1430|Location.Y=930|Color=128